(kicad_sch
	(version 20250114)
	(generator "eeschema")
	(generator_version "9.0")
	(paper "A3")
	(title_block
		(title "Thunderbolt to 10GbE adapter")
		(date "2026-04-23")
		(rev "1.1.0")
		(company "Antmicro Ltd")
		(comment 1 "www.antmicro.com")
	)
	(text "Hysteresis:\n* Threshold low -> high: 0.366V\n* Threshold high -> low: 0.296V"
		(exclude_from_sim no)
		(at 275.59 175.26 0)
		(effects
			(font
				(size 1.27 1.27)
			)
			(justify left bottom)
		)
	)
	(text "Thunderbolt Controller - Power"
		(exclude_from_sim no)
		(at 172.72 63.5 0)
		(effects
			(font
				(size 2.54 2.54)
				(thickness 0.508)
				(bold yes)
			)
			(justify left bottom)
		)
	)
	(junction
		(at 265.43 138.43)
		(diameter 0)
		(color 0 0 0 0)
	)
	(junction
		(at 243.84 217.17)
		(diameter 0)
		(color 0 0 0 0)
	)
	(junction
		(at 271.78 71.12)
		(diameter 0)
		(color 0 0 0 0)
	)
	(junction
		(at 167.64 102.87)
		(diameter 0)
		(color 0 0 0 0)
	)
	(junction
		(at 162.56 102.87)
		(diameter 0)
		(color 0 0 0 0)
	)
	(junction
		(at 252.73 120.65)
		(diameter 0)
		(color 0 0 0 0)
	)
	(junction
		(at 223.52 123.19)
		(diameter 0)
		(color 0 0 0 0)
	)
	(junction
		(at 227.33 71.12)
		(diameter 0)
		(color 0 0 0 0)
	)
	(junction
		(at 252.73 102.87)
		(diameter 0)
		(color 0 0 0 0)
	)
	(junction
		(at 292.1 160.02)
		(diameter 0)
		(color 0 0 0 0)
	)
	(junction
		(at 259.08 102.87)
		(diameter 0)
		(color 0 0 0 0)
	)
	(junction
		(at 233.68 156.21)
		(diameter 0)
		(color 0 0 0 0)
	)
	(junction
		(at 233.68 138.43)
		(diameter 0)
		(color 0 0 0 0)
	)
	(junction
		(at 167.64 85.09)
		(diameter 0)
		(color 0 0 0 0)
	)
	(junction
		(at 240.03 156.21)
		(diameter 0)
		(color 0 0 0 0)
	)
	(junction
		(at 147.32 102.87)
		(diameter 0)
		(color 0 0 0 0)
	)
	(junction
		(at 246.38 71.12)
		(diameter 0)
		(color 0 0 0 0)
	)
	(junction
		(at 233.68 120.65)
		(diameter 0)
		(color 0 0 0 0)
	)
	(junction
		(at 260.35 138.43)
		(diameter 0)
		(color 0 0 0 0)
	)
	(junction
		(at 260.35 120.65)
		(diameter 0)
		(color 0 0 0 0)
	)
	(junction
		(at 162.56 120.65)
		(diameter 0)
		(color 0 0 0 0)
	)
	(junction
		(at 161.29 158.75)
		(diameter 0)
		(color 0 0 0 0)
	)
	(junction
		(at 233.68 87.63)
		(diameter 0)
		(color 0 0 0 0)
	)
	(junction
		(at 147.32 85.09)
		(diameter 0)
		(color 0 0 0 0)
	)
	(junction
		(at 265.43 71.12)
		(diameter 0)
		(color 0 0 0 0)
	)
	(junction
		(at 167.64 87.63)
		(diameter 0)
		(color 0 0 0 0)
	)
	(junction
		(at 142.24 102.87)
		(diameter 0)
		(color 0 0 0 0)
	)
	(junction
		(at 153.67 215.9)
		(diameter 0)
		(color 0 0 0 0)
	)
	(junction
		(at 252.73 138.43)
		(diameter 0)
		(color 0 0 0 0)
	)
	(junction
		(at 233.68 71.12)
		(diameter 0)
		(color 0 0 0 0)
	)
	(junction
		(at 246.38 120.65)
		(diameter 0)
		(color 0 0 0 0)
	)
	(junction
		(at 240.03 120.65)
		(diameter 0)
		(color 0 0 0 0)
	)
	(junction
		(at 152.4 85.09)
		(diameter 0)
		(color 0 0 0 0)
	)
	(junction
		(at 147.32 138.43)
		(diameter 0)
		(color 0 0 0 0)
	)
	(junction
		(at 223.52 156.21)
		(diameter 0)
		(color 0 0 0 0)
	)
	(junction
		(at 157.48 102.87)
		(diameter 0)
		(color 0 0 0 0)
	)
	(junction
		(at 255.27 102.87)
		(diameter 0)
		(color 0 0 0 0)
	)
	(junction
		(at 152.4 102.87)
		(diameter 0)
		(color 0 0 0 0)
	)
	(junction
		(at 246.38 102.87)
		(diameter 0)
		(color 0 0 0 0)
	)
	(junction
		(at 154.94 85.09)
		(diameter 0)
		(color 0 0 0 0)
	)
	(junction
		(at 246.38 156.21)
		(diameter 0)
		(color 0 0 0 0)
	)
	(junction
		(at 227.33 87.63)
		(diameter 0)
		(color 0 0 0 0)
	)
	(junction
		(at 262.89 161.29)
		(diameter 0)
		(color 0 0 0 0)
	)
	(junction
		(at 275.59 153.67)
		(diameter 0)
		(color 0 0 0 0)
	)
	(junction
		(at 142.24 85.09)
		(diameter 0)
		(color 0 0 0 0)
	)
	(junction
		(at 227.33 120.65)
		(diameter 0)
		(color 0 0 0 0)
	)
	(junction
		(at 162.56 85.09)
		(diameter 0)
		(color 0 0 0 0)
	)
	(junction
		(at 240.03 138.43)
		(diameter 0)
		(color 0 0 0 0)
	)
	(junction
		(at 167.64 105.41)
		(diameter 0)
		(color 0 0 0 0)
	)
	(junction
		(at 279.4 71.12)
		(diameter 0)
		(color 0 0 0 0)
	)
	(junction
		(at 240.03 71.12)
		(diameter 0)
		(color 0 0 0 0)
	)
	(junction
		(at 252.73 71.12)
		(diameter 0)
		(color 0 0 0 0)
	)
	(junction
		(at 226.06 156.21)
		(diameter 0)
		(color 0 0 0 0)
	)
	(junction
		(at 246.38 138.43)
		(diameter 0)
		(color 0 0 0 0)
	)
	(junction
		(at 157.48 138.43)
		(diameter 0)
		(color 0 0 0 0)
	)
	(junction
		(at 162.56 138.43)
		(diameter 0)
		(color 0 0 0 0)
	)
	(junction
		(at 153.67 222.25)
		(diameter 0)
		(color 0 0 0 0)
	)
	(junction
		(at 157.48 85.09)
		(diameter 0)
		(color 0 0 0 0)
	)
	(junction
		(at 157.48 120.65)
		(diameter 0)
		(color 0 0 0 0)
	)
	(junction
		(at 269.24 102.87)
		(diameter 0)
		(color 0 0 0 0)
	)
	(junction
		(at 153.67 156.21)
		(diameter 0)
		(color 0 0 0 0)
	)
	(junction
		(at 222.25 87.63)
		(diameter 0)
		(color 0 0 0 0)
	)
	(junction
		(at 226.06 105.41)
		(diameter 0)
		(color 0 0 0 0)
	)
	(junction
		(at 259.08 71.12)
		(diameter 0)
		(color 0 0 0 0)
	)
	(junction
		(at 152.4 138.43)
		(diameter 0)
		(color 0 0 0 0)
	)
	(junction
		(at 223.52 120.65)
		(diameter 0)
		(color 0 0 0 0)
	)
	(wire
		(pts
			(xy 265.43 71.12) (xy 271.78 71.12)
		)
		(stroke
			(width 0)
			(type default)
		)
	)
	(wire
		(pts
			(xy 240.03 120.65) (xy 240.03 123.19)
		)
		(stroke
			(width 0)
			(type default)
		)
	)
	(wire
		(pts
			(xy 153.67 213.36) (xy 153.67 215.9)
		)
		(stroke
			(width 0)
			(type default)
		)
	)
	(wire
		(pts
			(xy 152.4 93.98) (xy 152.4 96.52)
		)
		(stroke
			(width 0)
			(type default)
		)
	)
	(wire
		(pts
			(xy 152.4 138.43) (xy 152.4 142.24)
		)
		(stroke
			(width 0)
			(type default)
		)
	)
	(wire
		(pts
			(xy 162.56 93.98) (xy 162.56 96.52)
		)
		(stroke
			(width 0)
			(type default)
		)
	)
	(wire
		(pts
			(xy 233.68 138.43) (xy 233.68 142.24)
		)
		(stroke
			(width 0)
			(type default)
		)
	)
	(wire
		(pts
			(xy 240.03 156.21) (xy 240.03 160.02)
		)
		(stroke
			(width 0)
			(type default)
		)
	)
	(wire
		(pts
			(xy 265.43 137.16) (xy 265.43 138.43)
		)
		(stroke
			(width 0)
			(type default)
		)
	)
	(wire
		(pts
			(xy 162.56 102.87) (xy 162.56 106.68)
		)
		(stroke
			(width 0)
			(type default)
		)
	)
	(wire
		(pts
			(xy 233.68 120.65) (xy 233.68 123.19)
		)
		(stroke
			(width 0)
			(type default)
		)
	)
	(wire
		(pts
			(xy 275.59 138.43) (xy 275.59 143.51)
		)
		(stroke
			(width 0)
			(type default)
		)
	)
	(wire
		(pts
			(xy 240.03 71.12) (xy 240.03 73.66)
		)
		(stroke
			(width 0)
			(type default)
		)
	)
	(wire
		(pts
			(xy 233.68 78.74) (xy 233.68 80.01)
		)
		(stroke
			(width 0)
			(type default)
		)
	)
	(wire
		(pts
			(xy 246.38 71.12) (xy 252.73 71.12)
		)
		(stroke
			(width 0)
			(type default)
		)
	)
	(wire
		(pts
			(xy 265.43 71.12) (xy 265.43 73.66)
		)
		(stroke
			(width 0)
			(type default)
		)
	)
	(wire
		(pts
			(xy 266.7 102.87) (xy 269.24 102.87)
		)
		(stroke
			(width 0)
			(type default)
		)
	)
	(wire
		(pts
			(xy 147.32 102.87) (xy 152.4 102.87)
		)
		(stroke
			(width 0)
			(type default)
		)
	)
	(wire
		(pts
			(xy 166.37 166.37) (xy 167.64 166.37)
		)
		(stroke
			(width 0)
			(type default)
		)
	)
	(wire
		(pts
			(xy 227.33 95.25) (xy 227.33 97.79)
		)
		(stroke
			(width 0)
			(type default)
		)
	)
	(wire
		(pts
			(xy 222.25 71.12) (xy 227.33 71.12)
		)
		(stroke
			(width 0)
			(type default)
		)
	)
	(wire
		(pts
			(xy 252.73 128.27) (xy 252.73 129.54)
		)
		(stroke
			(width 0)
			(type default)
		)
	)
	(wire
		(pts
			(xy 142.24 85.09) (xy 142.24 88.9)
		)
		(stroke
			(width 0)
			(type default)
		)
	)
	(wire
		(pts
			(xy 167.64 102.87) (xy 162.56 102.87)
		)
		(stroke
			(width 0)
			(type default)
		)
	)
	(wire
		(pts
			(xy 246.38 165.1) (xy 246.38 168.91)
		)
		(stroke
			(width 0)
			(type default)
		)
	)
	(wire
		(pts
			(xy 243.84 224.79) (xy 243.84 227.33)
		)
		(stroke
			(width 0)
			(type default)
		)
	)
	(wire
		(pts
			(xy 252.73 138.43) (xy 260.35 138.43)
		)
		(stroke
			(width 0)
			(type default)
		)
	)
	(wire
		(pts
			(xy 166.37 166.37) (xy 166.37 168.91)
		)
		(stroke
			(width 0)
			(type default)
		)
	)
	(wire
		(pts
			(xy 246.38 156.21) (xy 252.73 156.21)
		)
		(stroke
			(width 0)
			(type default)
		)
	)
	(wire
		(pts
			(xy 160.02 218.44) (xy 160.02 215.9)
		)
		(stroke
			(width 0)
			(type default)
		)
	)
	(wire
		(pts
			(xy 254 209.55) (xy 254 212.09)
		)
		(stroke
			(width 0)
			(type default)
		)
	)
	(wire
		(pts
			(xy 252.73 156.21) (xy 252.73 160.02)
		)
		(stroke
			(width 0)
			(type default)
		)
	)
	(wire
		(pts
			(xy 153.67 215.9) (xy 160.02 215.9)
		)
		(stroke
			(width 0)
			(type default)
		)
	)
	(wire
		(pts
			(xy 262.89 161.29) (xy 262.89 162.56)
		)
		(stroke
			(width 0)
			(type default)
		)
	)
	(wire
		(pts
			(xy 246.38 156.21) (xy 246.38 160.02)
		)
		(stroke
			(width 0)
			(type default)
		)
	)
	(wire
		(pts
			(xy 226.06 105.41) (xy 228.6 105.41)
		)
		(stroke
			(width 0)
			(type default)
		)
	)
	(wire
		(pts
			(xy 240.03 165.1) (xy 240.03 168.91)
		)
		(stroke
			(width 0)
			(type default)
		)
	)
	(wire
		(pts
			(xy 147.32 147.32) (xy 147.32 148.59)
		)
		(stroke
			(width 0)
			(type default)
		)
	)
	(wire
		(pts
			(xy 162.56 85.09) (xy 162.56 88.9)
		)
		(stroke
			(width 0)
			(type default)
		)
	)
	(wire
		(pts
			(xy 271.78 78.74) (xy 271.78 80.01)
		)
		(stroke
			(width 0)
			(type default)
		)
	)
	(wire
		(pts
			(xy 252.73 120.65) (xy 252.73 123.19)
		)
		(stroke
			(width 0)
			(type default)
		)
	)
	(wire
		(pts
			(xy 224.79 166.37) (xy 222.25 166.37)
		)
		(stroke
			(width 0)
			(type default)
		)
	)
	(wire
		(pts
			(xy 167.64 102.87) (xy 167.64 105.41)
		)
		(stroke
			(width 0)
			(type default)
		)
	)
	(wire
		(pts
			(xy 233.68 156.21) (xy 240.03 156.21)
		)
		(stroke
			(width 0)
			(type default)
		)
	)
	(wire
		(pts
			(xy 157.48 120.65) (xy 162.56 120.65)
		)
		(stroke
			(width 0)
			(type default)
		)
	)
	(wire
		(pts
			(xy 226.06 106.68) (xy 226.06 105.41)
		)
		(stroke
			(width 0)
			(type default)
		)
	)
	(wire
		(pts
			(xy 246.38 120.65) (xy 246.38 123.19)
		)
		(stroke
			(width 0)
			(type default)
		)
	)
	(wire
		(pts
			(xy 153.67 215.9) (xy 153.67 217.17)
		)
		(stroke
			(width 0)
			(type default)
		)
	)
	(wire
		(pts
			(xy 241.3 217.17) (xy 243.84 217.17)
		)
		(stroke
			(width 0)
			(type default)
		)
	)
	(wire
		(pts
			(xy 252.73 102.87) (xy 252.73 105.41)
		)
		(stroke
			(width 0)
			(type default)
		)
	)
	(wire
		(pts
			(xy 287.02 153.67) (xy 292.1 153.67)
		)
		(stroke
			(width 0)
			(type default)
		)
	)
	(wire
		(pts
			(xy 162.56 85.09) (xy 157.48 85.09)
		)
		(stroke
			(width 0)
			(type default)
		)
	)
	(wire
		(pts
			(xy 227.33 71.12) (xy 233.68 71.12)
		)
		(stroke
			(width 0)
			(type default)
		)
	)
	(wire
		(pts
			(xy 262.89 160.02) (xy 262.89 161.29)
		)
		(stroke
			(width 0)
			(type default)
		)
	)
	(wire
		(pts
			(xy 137.16 93.98) (xy 137.16 96.52)
		)
		(stroke
			(width 0)
			(type default)
		)
	)
	(wire
		(pts
			(xy 259.08 102.87) (xy 261.62 102.87)
		)
		(stroke
			(width 0)
			(type default)
		)
	)
	(wire
		(pts
			(xy 227.33 87.63) (xy 233.68 87.63)
		)
		(stroke
			(width 0)
			(type default)
		)
	)
	(wire
		(pts
			(xy 252.73 102.87) (xy 255.27 102.87)
		)
		(stroke
			(width 0)
			(type default)
		)
	)
	(wire
		(pts
			(xy 152.4 138.43) (xy 157.48 138.43)
		)
		(stroke
			(width 0)
			(type default)
		)
	)
	(wire
		(pts
			(xy 284.48 101.6) (xy 284.48 102.87)
		)
		(stroke
			(width 0)
			(type default)
		)
	)
	(wire
		(pts
			(xy 162.56 111.76) (xy 162.56 114.3)
		)
		(stroke
			(width 0)
			(type default)
		)
	)
	(wire
		(pts
			(xy 227.33 78.74) (xy 227.33 80.01)
		)
		(stroke
			(width 0)
			(type default)
		)
	)
	(wire
		(pts
			(xy 152.4 102.87) (xy 152.4 106.68)
		)
		(stroke
			(width 0)
			(type default)
		)
	)
	(wire
		(pts
			(xy 137.16 85.09) (xy 142.24 85.09)
		)
		(stroke
			(width 0)
			(type default)
		)
	)
	(wire
		(pts
			(xy 275.59 148.59) (xy 275.59 153.67)
		)
		(stroke
			(width 0)
			(type default)
		)
	)
	(wire
		(pts
			(xy 255.27 102.87) (xy 259.08 102.87)
		)
		(stroke
			(width 0)
			(type default)
		)
	)
	(wire
		(pts
			(xy 134.62 120.65) (xy 157.48 120.65)
		)
		(stroke
			(width 0)
			(type default)
		)
	)
	(wire
		(pts
			(xy 222.25 71.12) (xy 222.25 85.09)
		)
		(stroke
			(width 0)
			(type default)
		)
	)
	(wire
		(pts
			(xy 134.62 137.16) (xy 134.62 138.43)
		)
		(stroke
			(width 0)
			(type default)
		)
	)
	(wire
		(pts
			(xy 240.03 120.65) (xy 246.38 120.65)
		)
		(stroke
			(width 0)
			(type default)
		)
	)
	(wire
		(pts
			(xy 137.16 85.09) (xy 137.16 88.9)
		)
		(stroke
			(width 0)
			(type default)
		)
	)
	(wire
		(pts
			(xy 246.38 138.43) (xy 252.73 138.43)
		)
		(stroke
			(width 0)
			(type default)
		)
	)
	(wire
		(pts
			(xy 224.79 140.97) (xy 224.79 143.51)
		)
		(stroke
			(width 0)
			(type default)
		)
	)
	(wire
		(pts
			(xy 160.02 220.98) (xy 160.02 222.25)
		)
		(stroke
			(width 0)
			(type default)
		)
	)
	(wire
		(pts
			(xy 233.68 147.32) (xy 233.68 148.59)
		)
		(stroke
			(width 0)
			(type default)
		)
	)
	(wire
		(pts
			(xy 243.84 217.17) (xy 243.84 219.71)
		)
		(stroke
			(width 0)
			(type default)
		)
	)
	(wire
		(pts
			(xy 223.52 123.19) (xy 222.25 123.19)
		)
		(stroke
			(width 0)
			(type default)
		)
	)
	(wire
		(pts
			(xy 252.73 71.12) (xy 252.73 73.66)
		)
		(stroke
			(width 0)
			(type default)
		)
	)
	(wire
		(pts
			(xy 162.56 102.87) (xy 157.48 102.87)
		)
		(stroke
			(width 0)
			(type default)
		)
	)
	(wire
		(pts
			(xy 142.24 102.87) (xy 142.24 106.68)
		)
		(stroke
			(width 0)
			(type default)
		)
	)
	(wire
		(pts
			(xy 233.68 87.63) (xy 233.68 90.17)
		)
		(stroke
			(width 0)
			(type default)
		)
	)
	(wire
		(pts
			(xy 271.78 71.12) (xy 271.78 73.66)
		)
		(stroke
			(width 0)
			(type default)
		)
	)
	(wire
		(pts
			(xy 240.03 156.21) (xy 246.38 156.21)
		)
		(stroke
			(width 0)
			(type default)
		)
	)
	(wire
		(pts
			(xy 223.52 120.65) (xy 222.25 120.65)
		)
		(stroke
			(width 0)
			(type default)
		)
	)
	(wire
		(pts
			(xy 229.87 138.43) (xy 233.68 138.43)
		)
		(stroke
			(width 0)
			(type default)
		)
	)
	(wire
		(pts
			(xy 223.52 120.65) (xy 227.33 120.65)
		)
		(stroke
			(width 0)
			(type default)
		)
	)
	(wire
		(pts
			(xy 227.33 120.65) (xy 227.33 123.19)
		)
		(stroke
			(width 0)
			(type default)
		)
	)
	(wire
		(pts
			(xy 222.25 140.97) (xy 224.79 140.97)
		)
		(stroke
			(width 0)
			(type default)
		)
	)
	(wire
		(pts
			(xy 246.38 71.12) (xy 246.38 73.66)
		)
		(stroke
			(width 0)
			(type default)
		)
	)
	(wire
		(pts
			(xy 153.67 222.25) (xy 160.02 222.25)
		)
		(stroke
			(width 0)
			(type default)
		)
	)
	(wire
		(pts
			(xy 223.52 158.75) (xy 222.25 158.75)
		)
		(stroke
			(width 0)
			(type default)
		)
	)
	(wire
		(pts
			(xy 142.24 111.76) (xy 142.24 114.3)
		)
		(stroke
			(width 0)
			(type default)
		)
	)
	(wire
		(pts
			(xy 138.43 213.36) (xy 138.43 217.17)
		)
		(stroke
			(width 0)
			(type default)
		)
	)
	(wire
		(pts
			(xy 152.4 147.32) (xy 152.4 148.59)
		)
		(stroke
			(width 0)
			(type default)
		)
	)
	(wire
		(pts
			(xy 134.62 138.43) (xy 147.32 138.43)
		)
		(stroke
			(width 0)
			(type default)
		)
	)
	(wire
		(pts
			(xy 162.56 120.65) (xy 162.56 124.46)
		)
		(stroke
			(width 0)
			(type default)
		)
	)
	(wire
		(pts
			(xy 269.24 102.87) (xy 284.48 102.87)
		)
		(stroke
			(width 0)
			(type default)
		)
	)
	(wire
		(pts
			(xy 161.29 220.98) (xy 160.02 220.98)
		)
		(stroke
			(width 0)
			(type default)
		)
	)
	(wire
		(pts
			(xy 167.64 85.09) (xy 167.64 87.63)
		)
		(stroke
			(width 0)
			(type default)
		)
	)
	(wire
		(pts
			(xy 233.68 71.12) (xy 240.03 71.12)
		)
		(stroke
			(width 0)
			(type default)
		)
	)
	(wire
		(pts
			(xy 265.43 138.43) (xy 275.59 138.43)
		)
		(stroke
			(width 0)
			(type default)
		)
	)
	(wire
		(pts
			(xy 222.25 87.63) (xy 222.25 90.17)
		)
		(stroke
			(width 0)
			(type default)
		)
	)
	(wire
		(pts
			(xy 152.4 85.09) (xy 152.4 88.9)
		)
		(stroke
			(width 0)
			(type default)
		)
	)
	(wire
		(pts
			(xy 162.56 129.54) (xy 162.56 132.08)
		)
		(stroke
			(width 0)
			(type default)
		)
	)
	(wire
		(pts
			(xy 154.94 83.82) (xy 154.94 85.09)
		)
		(stroke
			(width 0)
			(type default)
		)
	)
	(wire
		(pts
			(xy 240.03 138.43) (xy 246.38 138.43)
		)
		(stroke
			(width 0)
			(type default)
		)
	)
	(wire
		(pts
			(xy 262.89 153.67) (xy 262.89 154.94)
		)
		(stroke
			(width 0)
			(type default)
		)
	)
	(wire
		(pts
			(xy 252.73 71.12) (xy 259.08 71.12)
		)
		(stroke
			(width 0)
			(type default)
		)
	)
	(wire
		(pts
			(xy 233.68 71.12) (xy 233.68 73.66)
		)
		(stroke
			(width 0)
			(type default)
		)
	)
	(wire
		(pts
			(xy 161.29 218.44) (xy 160.02 218.44)
		)
		(stroke
			(width 0)
			(type default)
		)
	)
	(wire
		(pts
			(xy 233.68 138.43) (xy 240.03 138.43)
		)
		(stroke
			(width 0)
			(type default)
		)
	)
	(wire
		(pts
			(xy 224.79 166.37) (xy 224.79 168.91)
		)
		(stroke
			(width 0)
			(type default)
		)
	)
	(wire
		(pts
			(xy 153.67 156.21) (xy 153.67 162.56)
		)
		(stroke
			(width 0)
			(type default)
		)
	)
	(wire
		(pts
			(xy 167.64 156.21) (xy 153.67 156.21)
		)
		(stroke
			(width 0)
			(type default)
		)
	)
	(wire
		(pts
			(xy 260.35 138.43) (xy 265.43 138.43)
		)
		(stroke
			(width 0)
			(type default)
		)
	)
	(wire
		(pts
			(xy 252.73 78.74) (xy 252.73 80.01)
		)
		(stroke
			(width 0)
			(type default)
		)
	)
	(wire
		(pts
			(xy 147.32 85.09) (xy 152.4 85.09)
		)
		(stroke
			(width 0)
			(type default)
		)
	)
	(wire
		(pts
			(xy 240.03 138.43) (xy 240.03 142.24)
		)
		(stroke
			(width 0)
			(type default)
		)
	)
	(wire
		(pts
			(xy 259.08 110.49) (xy 259.08 113.03)
		)
		(stroke
			(width 0)
			(type default)
		)
	)
	(wire
		(pts
			(xy 147.32 102.87) (xy 147.32 106.68)
		)
		(stroke
			(width 0)
			(type default)
		)
	)
	(wire
		(pts
			(xy 275.59 158.75) (xy 279.4 158.75)
		)
		(stroke
			(width 0)
			(type default)
		)
	)
	(wire
		(pts
			(xy 147.32 138.43) (xy 152.4 138.43)
		)
		(stroke
			(width 0)
			(type default)
		)
	)
	(wire
		(pts
			(xy 227.33 120.65) (xy 233.68 120.65)
		)
		(stroke
			(width 0)
			(type default)
		)
	)
	(wire
		(pts
			(xy 147.32 111.76) (xy 147.32 114.3)
		)
		(stroke
			(width 0)
			(type default)
		)
	)
	(wire
		(pts
			(xy 162.56 147.32) (xy 162.56 148.59)
		)
		(stroke
			(width 0)
			(type default)
		)
	)
	(wire
		(pts
			(xy 223.52 156.21) (xy 226.06 156.21)
		)
		(stroke
			(width 0)
			(type default)
		)
	)
	(wire
		(pts
			(xy 252.73 120.65) (xy 260.35 120.65)
		)
		(stroke
			(width 0)
			(type default)
		)
	)
	(wire
		(pts
			(xy 142.24 93.98) (xy 142.24 96.52)
		)
		(stroke
			(width 0)
			(type default)
		)
	)
	(wire
		(pts
			(xy 275.59 153.67) (xy 275.59 158.75)
		)
		(stroke
			(width 0)
			(type default)
		)
	)
	(wire
		(pts
			(xy 226.06 156.21) (xy 233.68 156.21)
		)
		(stroke
			(width 0)
			(type default)
		)
	)
	(wire
		(pts
			(xy 292.1 153.67) (xy 292.1 160.02)
		)
		(stroke
			(width 0)
			(type default)
		)
	)
	(wire
		(pts
			(xy 157.48 111.76) (xy 157.48 114.3)
		)
		(stroke
			(width 0)
			(type default)
		)
	)
	(wire
		(pts
			(xy 222.25 87.63) (xy 227.33 87.63)
		)
		(stroke
			(width 0)
			(type default)
		)
	)
	(wire
		(pts
			(xy 223.52 156.21) (xy 223.52 158.75)
		)
		(stroke
			(width 0)
			(type default)
		)
	)
	(wire
		(pts
			(xy 153.67 167.64) (xy 153.67 168.91)
		)
		(stroke
			(width 0)
			(type default)
		)
	)
	(wire
		(pts
			(xy 233.68 120.65) (xy 240.03 120.65)
		)
		(stroke
			(width 0)
			(type default)
		)
	)
	(wire
		(pts
			(xy 162.56 138.43) (xy 167.64 138.43)
		)
		(stroke
			(width 0)
			(type default)
		)
	)
	(wire
		(pts
			(xy 157.48 93.98) (xy 157.48 96.52)
		)
		(stroke
			(width 0)
			(type default)
		)
	)
	(wire
		(pts
			(xy 233.68 217.17) (xy 236.22 217.17)
		)
		(stroke
			(width 0)
			(type default)
		)
	)
	(wire
		(pts
			(xy 138.43 222.25) (xy 138.43 224.79)
		)
		(stroke
			(width 0)
			(type default)
		)
	)
	(wire
		(pts
			(xy 157.48 129.54) (xy 157.48 132.08)
		)
		(stroke
			(width 0)
			(type default)
		)
	)
	(wire
		(pts
			(xy 265.43 78.74) (xy 265.43 80.01)
		)
		(stroke
			(width 0)
			(type default)
		)
	)
	(wire
		(pts
			(xy 252.73 138.43) (xy 252.73 142.24)
		)
		(stroke
			(width 0)
			(type default)
		)
	)
	(wire
		(pts
			(xy 157.48 138.43) (xy 162.56 138.43)
		)
		(stroke
			(width 0)
			(type default)
		)
	)
	(wire
		(pts
			(xy 222.25 138.43) (xy 224.79 138.43)
		)
		(stroke
			(width 0)
			(type default)
		)
	)
	(wire
		(pts
			(xy 240.03 78.74) (xy 240.03 80.01)
		)
		(stroke
			(width 0)
			(type default)
		)
	)
	(wire
		(pts
			(xy 279.4 68.58) (xy 279.4 71.12)
		)
		(stroke
			(width 0)
			(type default)
		)
	)
	(wire
		(pts
			(xy 233.68 165.1) (xy 233.68 168.91)
		)
		(stroke
			(width 0)
			(type default)
		)
	)
	(wire
		(pts
			(xy 246.38 78.74) (xy 246.38 80.01)
		)
		(stroke
			(width 0)
			(type default)
		)
	)
	(wire
		(pts
			(xy 161.29 158.75) (xy 161.29 162.56)
		)
		(stroke
			(width 0)
			(type default)
		)
	)
	(wire
		(pts
			(xy 292.1 160.02) (xy 289.56 160.02)
		)
		(stroke
			(width 0)
			(type default)
		)
	)
	(wire
		(pts
			(xy 246.38 120.65) (xy 252.73 120.65)
		)
		(stroke
			(width 0)
			(type default)
		)
	)
	(wire
		(pts
			(xy 226.06 111.76) (xy 226.06 113.03)
		)
		(stroke
			(width 0)
			(type default)
		)
	)
	(wire
		(pts
			(xy 259.08 71.12) (xy 259.08 73.66)
		)
		(stroke
			(width 0)
			(type default)
		)
	)
	(wire
		(pts
			(xy 223.52 125.73) (xy 222.25 125.73)
		)
		(stroke
			(width 0)
			(type default)
		)
	)
	(wire
		(pts
			(xy 252.73 110.49) (xy 252.73 113.03)
		)
		(stroke
			(width 0)
			(type default)
		)
	)
	(wire
		(pts
			(xy 137.16 102.87) (xy 142.24 102.87)
		)
		(stroke
			(width 0)
			(type default)
		)
	)
	(wire
		(pts
			(xy 157.48 120.65) (xy 157.48 124.46)
		)
		(stroke
			(width 0)
			(type default)
		)
	)
	(wire
		(pts
			(xy 269.24 110.49) (xy 269.24 113.03)
		)
		(stroke
			(width 0)
			(type default)
		)
	)
	(wire
		(pts
			(xy 260.35 120.65) (xy 260.35 138.43)
		)
		(stroke
			(width 0)
			(type default)
		)
	)
	(wire
		(pts
			(xy 223.52 120.65) (xy 223.52 123.19)
		)
		(stroke
			(width 0)
			(type default)
		)
	)
	(wire
		(pts
			(xy 227.33 71.12) (xy 227.33 73.66)
		)
		(stroke
			(width 0)
			(type default)
		)
	)
	(wire
		(pts
			(xy 153.67 222.25) (xy 153.67 224.79)
		)
		(stroke
			(width 0)
			(type default)
		)
	)
	(wire
		(pts
			(xy 243.84 217.17) (xy 247.65 217.17)
		)
		(stroke
			(width 0)
			(type default)
		)
	)
	(wire
		(pts
			(xy 233.68 156.21) (xy 233.68 160.02)
		)
		(stroke
			(width 0)
			(type default)
		)
	)
	(wire
		(pts
			(xy 255.27 101.6) (xy 255.27 102.87)
		)
		(stroke
			(width 0)
			(type default)
		)
	)
	(wire
		(pts
			(xy 259.08 102.87) (xy 259.08 105.41)
		)
		(stroke
			(width 0)
			(type default)
		)
	)
	(wire
		(pts
			(xy 142.24 102.87) (xy 147.32 102.87)
		)
		(stroke
			(width 0)
			(type default)
		)
	)
	(wire
		(pts
			(xy 246.38 128.27) (xy 246.38 129.54)
		)
		(stroke
			(width 0)
			(type default)
		)
	)
	(wire
		(pts
			(xy 281.94 153.67) (xy 275.59 153.67)
		)
		(stroke
			(width 0)
			(type default)
		)
	)
	(wire
		(pts
			(xy 226.06 105.41) (xy 222.25 105.41)
		)
		(stroke
			(width 0)
			(type default)
		)
	)
	(wire
		(pts
			(xy 223.52 123.19) (xy 223.52 125.73)
		)
		(stroke
			(width 0)
			(type default)
		)
	)
	(wire
		(pts
			(xy 154.94 85.09) (xy 152.4 85.09)
		)
		(stroke
			(width 0)
			(type default)
		)
	)
	(wire
		(pts
			(xy 262.89 161.29) (xy 279.4 161.29)
		)
		(stroke
			(width 0)
			(type default)
		)
	)
	(wire
		(pts
			(xy 252.73 147.32) (xy 252.73 148.59)
		)
		(stroke
			(width 0)
			(type default)
		)
	)
	(wire
		(pts
			(xy 147.32 138.43) (xy 147.32 142.24)
		)
		(stroke
			(width 0)
			(type default)
		)
	)
	(wire
		(pts
			(xy 233.68 95.25) (xy 233.68 97.79)
		)
		(stroke
			(width 0)
			(type default)
		)
	)
	(wire
		(pts
			(xy 162.56 138.43) (xy 162.56 142.24)
		)
		(stroke
			(width 0)
			(type default)
		)
	)
	(wire
		(pts
			(xy 167.64 105.41) (xy 167.64 107.95)
		)
		(stroke
			(width 0)
			(type default)
		)
	)
	(wire
		(pts
			(xy 240.03 71.12) (xy 246.38 71.12)
		)
		(stroke
			(width 0)
			(type default)
		)
	)
	(wire
		(pts
			(xy 269.24 102.87) (xy 269.24 105.41)
		)
		(stroke
			(width 0)
			(type default)
		)
	)
	(wire
		(pts
			(xy 167.64 87.63) (xy 167.64 90.17)
		)
		(stroke
			(width 0)
			(type default)
		)
	)
	(wire
		(pts
			(xy 254 222.25) (xy 254 227.33)
		)
		(stroke
			(width 0)
			(type default)
		)
	)
	(wire
		(pts
			(xy 227.33 87.63) (xy 227.33 90.17)
		)
		(stroke
			(width 0)
			(type default)
		)
	)
	(wire
		(pts
			(xy 167.64 85.09) (xy 162.56 85.09)
		)
		(stroke
			(width 0)
			(type default)
		)
	)
	(wire
		(pts
			(xy 226.06 156.21) (xy 226.06 157.48)
		)
		(stroke
			(width 0)
			(type default)
		)
	)
	(wire
		(pts
			(xy 292.1 160.02) (xy 297.18 160.02)
		)
		(stroke
			(width 0)
			(type default)
		)
	)
	(wire
		(pts
			(xy 271.78 71.12) (xy 279.4 71.12)
		)
		(stroke
			(width 0)
			(type default)
		)
	)
	(wire
		(pts
			(xy 259.08 78.74) (xy 259.08 80.01)
		)
		(stroke
			(width 0)
			(type default)
		)
	)
	(wire
		(pts
			(xy 152.4 158.75) (xy 161.29 158.75)
		)
		(stroke
			(width 0)
			(type default)
		)
	)
	(wire
		(pts
			(xy 157.48 102.87) (xy 152.4 102.87)
		)
		(stroke
			(width 0)
			(type default)
		)
	)
	(wire
		(pts
			(xy 254 195.58) (xy 254 196.85)
		)
		(stroke
			(width 0)
			(type default)
		)
	)
	(wire
		(pts
			(xy 152.4 156.21) (xy 153.67 156.21)
		)
		(stroke
			(width 0)
			(type default)
		)
	)
	(wire
		(pts
			(xy 161.29 158.75) (xy 167.64 158.75)
		)
		(stroke
			(width 0)
			(type default)
		)
	)
	(wire
		(pts
			(xy 152.4 111.76) (xy 152.4 114.3)
		)
		(stroke
			(width 0)
			(type default)
		)
	)
	(wire
		(pts
			(xy 246.38 147.32) (xy 246.38 148.59)
		)
		(stroke
			(width 0)
			(type default)
		)
	)
	(wire
		(pts
			(xy 262.89 167.64) (xy 262.89 168.91)
		)
		(stroke
			(width 0)
			(type default)
		)
	)
	(wire
		(pts
			(xy 246.38 102.87) (xy 252.73 102.87)
		)
		(stroke
			(width 0)
			(type default)
		)
	)
	(wire
		(pts
			(xy 252.73 165.1) (xy 252.73 168.91)
		)
		(stroke
			(width 0)
			(type default)
		)
	)
	(wire
		(pts
			(xy 157.48 138.43) (xy 157.48 142.24)
		)
		(stroke
			(width 0)
			(type default)
		)
	)
	(wire
		(pts
			(xy 157.48 147.32) (xy 157.48 148.59)
		)
		(stroke
			(width 0)
			(type default)
		)
	)
	(wire
		(pts
			(xy 147.32 93.98) (xy 147.32 96.52)
		)
		(stroke
			(width 0)
			(type default)
		)
	)
	(wire
		(pts
			(xy 246.38 102.87) (xy 246.38 105.41)
		)
		(stroke
			(width 0)
			(type default)
		)
	)
	(wire
		(pts
			(xy 246.38 110.49) (xy 246.38 113.03)
		)
		(stroke
			(width 0)
			(type default)
		)
	)
	(wire
		(pts
			(xy 233.68 128.27) (xy 233.68 129.54)
		)
		(stroke
			(width 0)
			(type default)
		)
	)
	(wire
		(pts
			(xy 134.62 119.38) (xy 134.62 120.65)
		)
		(stroke
			(width 0)
			(type default)
		)
	)
	(wire
		(pts
			(xy 279.4 87.63) (xy 279.4 71.12)
		)
		(stroke
			(width 0)
			(type default)
		)
	)
	(wire
		(pts
			(xy 161.29 167.64) (xy 161.29 168.91)
		)
		(stroke
			(width 0)
			(type default)
		)
	)
	(wire
		(pts
			(xy 222.25 102.87) (xy 246.38 102.87)
		)
		(stroke
			(width 0)
			(type default)
		)
	)
	(wire
		(pts
			(xy 223.52 156.21) (xy 222.25 156.21)
		)
		(stroke
			(width 0)
			(type default)
		)
	)
	(wire
		(pts
			(xy 233.68 87.63) (xy 279.4 87.63)
		)
		(stroke
			(width 0)
			(type default)
		)
	)
	(wire
		(pts
			(xy 240.03 128.27) (xy 240.03 129.54)
		)
		(stroke
			(width 0)
			(type default)
		)
	)
	(wire
		(pts
			(xy 254 201.93) (xy 254 204.47)
		)
		(stroke
			(width 0)
			(type default)
		)
	)
	(wire
		(pts
			(xy 142.24 85.09) (xy 147.32 85.09)
		)
		(stroke
			(width 0)
			(type default)
		)
	)
	(wire
		(pts
			(xy 246.38 138.43) (xy 246.38 142.24)
		)
		(stroke
			(width 0)
			(type default)
		)
	)
	(wire
		(pts
			(xy 157.48 102.87) (xy 157.48 106.68)
		)
		(stroke
			(width 0)
			(type default)
		)
	)
	(wire
		(pts
			(xy 157.48 85.09) (xy 157.48 88.9)
		)
		(stroke
			(width 0)
			(type default)
		)
	)
	(wire
		(pts
			(xy 259.08 71.12) (xy 265.43 71.12)
		)
		(stroke
			(width 0)
			(type default)
		)
	)
	(wire
		(pts
			(xy 162.56 120.65) (xy 167.64 120.65)
		)
		(stroke
			(width 0)
			(type default)
		)
	)
	(wire
		(pts
			(xy 147.32 85.09) (xy 147.32 88.9)
		)
		(stroke
			(width 0)
			(type default)
		)
	)
	(wire
		(pts
			(xy 240.03 147.32) (xy 240.03 148.59)
		)
		(stroke
			(width 0)
			(type default)
		)
	)
	(wire
		(pts
			(xy 227.33 128.27) (xy 227.33 129.54)
		)
		(stroke
			(width 0)
			(type default)
		)
	)
	(wire
		(pts
			(xy 157.48 85.09) (xy 154.94 85.09)
		)
		(stroke
			(width 0)
			(type default)
		)
	)
	(label "VCC_0P9"
		(at 275.59 138.43 180)
		(effects
			(font
				(size 1.27 1.27)
			)
			(justify right bottom)
		)
	)
	(hierarchical_label "0P9_BUFFERED"
		(shape output)
		(at 233.68 217.17 180)
		(effects
			(font
				(size 1.27 1.27)
			)
			(justify right)
		)
	)
	(hierarchical_label "0P9_BUFFERED"
		(shape output)
		(at 297.18 160.02 0)
		(effects
			(font
				(size 1.27 1.27)
			)
			(justify left)
		)
	)
	(symbol
		(lib_id "antmicropower:GND")
		(at 233.68 168.91 0)
		(unit 1)
		(exclude_from_sim no)
		(in_bom yes)
		(on_board yes)
		(dnp no)
		(fields_autoplaced yes)
		(property "Reference" "#PWR0114"
			(at 233.68 175.26 0)
			(effects
				(font
					(size 1.27 1.27)
				)
				(hide yes)
			)
		)
		(property "Value" "GND"
			(at 233.68 172.72 0)
			(effects
				(font
					(size 1.27 1.27)
				)
			)
		)
		(property "Footprint" ""
			(at 233.68 168.91 0)
			(effects
				(font
					(size 1.27 1.27)
				)
				(hide yes)
			)
		)
		(property "Datasheet" ""
			(at 233.68 168.91 0)
			(effects
				(font
					(size 1.27 1.27)
				)
				(hide yes)
			)
		)
		(property "Description" ""
			(at 233.68 168.91 0)
			(effects
				(font
					(size 1.27 1.27)
				)
				(hide yes)
			)
		)
		(property "Author" "Antmicro"
			(at 242.57 176.53 0)
			(effects
				(font
					(size 1.27 1.27)
					(thickness 0.15)
				)
				(justify left bottom)
				(hide yes)
			)
		)
		(property "License" "Apache-2.0"
			(at 242.57 179.07 0)
			(effects
				(font
					(size 1.27 1.27)
					(thickness 0.15)
				)
				(justify left bottom)
				(hide yes)
			)
		)
		(pin "1"
		)
		(instances
			(project "thunderbolt-to-10gbe-adapter"
				(path ""
					(reference "#PWR0114")
					(unit 1)
				)
			)
		)
	)
	(symbol
		(lib_id "antmicroCapacitors0402:C_1u_0402")
		(at 246.38 128.27 90)
		(unit 1)
		(exclude_from_sim no)
		(in_bom yes)
		(on_board yes)
		(dnp no)
		(property "Reference" "C88"
			(at 247.015 123.825 90)
			(effects
				(font
					(size 1.27 1.27)
					(thickness 0.15)
				)
				(justify right)
			)
		)
		(property "Value" "C_1u_0402"
			(at 256.54 107.95 0)
			(effects
				(font
					(size 1.27 1.27)
					(thickness 0.15)
				)
				(justify left bottom)
				(hide yes)
			)
		)
		(property "Footprint" "antmicro-footprints:C_0402_1005Metric"
			(at 259.08 107.95 0)
			(effects
				(font
					(size 1.27 1.27)
					(thickness 0.15)
				)
				(justify left bottom)
				(hide yes)
			)
		)
		(property "Datasheet" "https://product.tdk.com/en/search/capacitor/ceramic/mlcc/info?part_no=C1005X6S1A105K050BC"
			(at 261.62 107.95 0)
			(effects
				(font
					(size 1.27 1.27)
					(thickness 0.15)
				)
				(justify left bottom)
				(hide yes)
			)
		)
		(property "Description" "SMD Multilayer Ceramic Capacitor, 1 µF, 10 V, 0402 [1005 Metric], ± 10%, X6S, C"
			(at 246.38 128.27 0)
			(effects
				(font
					(size 1.27 1.27)
				)
				(hide yes)
			)
		)
		(property "MPN" "C1005X6S1A105K050BC"
			(at 264.16 107.95 0)
			(effects
				(font
					(size 1.27 1.27)
					(thickness 0.15)
				)
				(justify left bottom)
				(hide yes)
			)
		)
		(property "Manufacturer" "TDK"
			(at 266.7 107.95 0)
			(effects
				(font
					(size 1.27 1.27)
					(thickness 0.15)
				)
				(justify left bottom)
				(hide yes)
			)
		)
		(property "License" "Apache-2.0"
			(at 269.24 107.95 0)
			(effects
				(font
					(size 1.27 1.27)
					(thickness 0.15)
				)
				(justify left bottom)
				(hide yes)
			)
		)
		(property "Val" "1u"
			(at 247.015 127.635 90)
			(effects
				(font
					(size 1.27 1.27)
					(thickness 0.15)
				)
				(justify right)
			)
		)
		(property "Voltage" ""
			(at 274.32 107.95 0)
			(effects
				(font
					(size 1.27 1.27)
				)
				(justify left bottom)
				(hide yes)
			)
		)
		(property "Dielectric" ""
			(at 276.86 107.95 0)
			(effects
				(font
					(size 1.27 1.27)
				)
				(justify left bottom)
				(hide yes)
			)
		)
		(property "Author" "Antmicro"
			(at 271.78 107.95 0)
			(effects
				(font
					(size 1.27 1.27)
					(thickness 0.15)
				)
				(justify left bottom)
				(hide yes)
			)
		)
		(pin "1"
		)
		(pin "2"
		)
		(instances
			(project "thunderbolt-to-10gbe-adapter"
				(path ""
					(reference "C88")
					(unit 1)
				)
			)
		)
	)
	(symbol
		(lib_id "antmicropower:GND")
		(at 240.03 129.54 0)
		(unit 1)
		(exclude_from_sim no)
		(in_bom yes)
		(on_board yes)
		(dnp no)
		(property "Reference" "#PWR0116"
			(at 240.03 135.89 0)
			(effects
				(font
					(size 1.27 1.27)
				)
				(hide yes)
			)
		)
		(property "Value" "GND"
			(at 240.03 133.35 0)
			(effects
				(font
					(size 1.27 1.27)
				)
			)
		)
		(property "Footprint" ""
			(at 240.03 129.54 0)
			(effects
				(font
					(size 1.27 1.27)
				)
				(hide yes)
			)
		)
		(property "Datasheet" ""
			(at 240.03 129.54 0)
			(effects
				(font
					(size 1.27 1.27)
				)
				(hide yes)
			)
		)
		(property "Description" ""
			(at 240.03 129.54 0)
			(effects
				(font
					(size 1.27 1.27)
				)
				(hide yes)
			)
		)
		(property "Author" "Antmicro"
			(at 248.92 137.16 0)
			(effects
				(font
					(size 1.27 1.27)
					(thickness 0.15)
				)
				(justify left bottom)
				(hide yes)
			)
		)
		(property "License" "Apache-2.0"
			(at 248.92 139.7 0)
			(effects
				(font
					(size 1.27 1.27)
					(thickness 0.15)
				)
				(justify left bottom)
				(hide yes)
			)
		)
		(pin "1"
		)
		(instances
			(project "thunderbolt-to-10gbe-adapter"
				(path ""
					(reference "#PWR0116")
					(unit 1)
				)
			)
		)
	)
	(symbol
		(lib_id "antmicropower:GND")
		(at 147.32 114.3 0)
		(unit 1)
		(exclude_from_sim no)
		(in_bom yes)
		(on_board yes)
		(dnp no)
		(property "Reference" "#PWR086"
			(at 147.32 120.65 0)
			(effects
				(font
					(size 1.27 1.27)
				)
				(hide yes)
			)
		)
		(property "Value" "GND"
			(at 147.32 118.11 0)
			(effects
				(font
					(size 1.27 1.27)
				)
			)
		)
		(property "Footprint" ""
			(at 147.32 114.3 0)
			(effects
				(font
					(size 1.27 1.27)
				)
				(hide yes)
			)
		)
		(property "Datasheet" ""
			(at 147.32 114.3 0)
			(effects
				(font
					(size 1.27 1.27)
				)
				(hide yes)
			)
		)
		(property "Description" ""
			(at 147.32 114.3 0)
			(effects
				(font
					(size 1.27 1.27)
				)
				(hide yes)
			)
		)
		(property "Author" "Antmicro"
			(at 156.21 121.92 0)
			(effects
				(font
					(size 1.27 1.27)
					(thickness 0.15)
				)
				(justify left bottom)
				(hide yes)
			)
		)
		(property "License" "Apache-2.0"
			(at 156.21 124.46 0)
			(effects
				(font
					(size 1.27 1.27)
					(thickness 0.15)
				)
				(justify left bottom)
				(hide yes)
			)
		)
		(pin "1"
		)
		(instances
			(project "thunderbolt-to-10gbe-adapter"
				(path ""
					(reference "#PWR086")
					(unit 1)
				)
			)
		)
	)
	(symbol
		(lib_id "antmicroCapacitors0402:C_100n_0402")
		(at 240.03 78.74 90)
		(unit 1)
		(exclude_from_sim no)
		(in_bom yes)
		(on_board yes)
		(dnp no)
		(property "Reference" "C91"
			(at 240.665 74.295 90)
			(effects
				(font
					(size 1.27 1.27)
					(thickness 0.15)
				)
				(justify right)
			)
		)
		(property "Value" "C_100n_0402"
			(at 250.19 58.42 0)
			(effects
				(font
					(size 1.27 1.27)
					(thickness 0.15)
				)
				(justify left bottom)
				(hide yes)
			)
		)
		(property "Footprint" "antmicro-footprints:C_0402_1005Metric"
			(at 252.73 58.42 0)
			(effects
				(font
					(size 1.27 1.27)
					(thickness 0.15)
				)
				(justify left bottom)
				(hide yes)
			)
		)
		(property "Datasheet" "https://www.murata.com/products/productdetail?partno=GRM155R61H104KE14%23"
			(at 255.27 58.42 0)
			(effects
				(font
					(size 1.27 1.27)
					(thickness 0.15)
				)
				(justify left bottom)
				(hide yes)
			)
		)
		(property "Description" "SMD Multilayer Ceramic Capacitor, 0.1 µF, 50 V, 0402 [1005 Metric], ± 10%, X5R, GRM Series"
			(at 240.03 78.74 0)
			(effects
				(font
					(size 1.27 1.27)
				)
				(hide yes)
			)
		)
		(property "MPN" "GRM155R61H104KE14D"
			(at 257.81 58.42 0)
			(effects
				(font
					(size 1.27 1.27)
					(thickness 0.15)
				)
				(justify left bottom)
				(hide yes)
			)
		)
		(property "Manufacturer" "Murata"
			(at 260.35 58.42 0)
			(effects
				(font
					(size 1.27 1.27)
					(thickness 0.15)
				)
				(justify left bottom)
				(hide yes)
			)
		)
		(property "License" "Apache-2.0"
			(at 262.89 58.42 0)
			(effects
				(font
					(size 1.27 1.27)
					(thickness 0.15)
				)
				(justify left bottom)
				(hide yes)
			)
		)
		(property "Val" "100n"
			(at 240.665 78.105 90)
			(effects
				(font
					(size 1.27 1.27)
					(thickness 0.15)
				)
				(justify right)
			)
		)
		(property "Voltage" "50V"
			(at 267.97 58.42 0)
			(effects
				(font
					(size 1.27 1.27)
				)
				(justify left bottom)
				(hide yes)
			)
		)
		(property "Dielectric" "X5R"
			(at 270.51 58.42 0)
			(effects
				(font
					(size 1.27 1.27)
				)
				(justify left bottom)
				(hide yes)
			)
		)
		(property "Author" "Antmicro"
			(at 265.43 58.42 0)
			(effects
				(font
					(size 1.27 1.27)
					(thickness 0.15)
				)
				(justify left bottom)
				(hide yes)
			)
		)
		(pin "1"
		)
		(pin "2"
		)
		(instances
			(project "thunderbolt-to-10gbe-adapter"
				(path ""
					(reference "C91")
					(unit 1)
				)
			)
		)
	)
	(symbol
		(lib_id "antmicroCapacitors0402:C_1u_0402")
		(at 157.48 129.54 90)
		(unit 1)
		(exclude_from_sim no)
		(in_bom yes)
		(on_board yes)
		(dnp no)
		(fields_autoplaced yes)
		(property "Reference" "C66"
			(at 154.94 125.7236 90)
			(effects
				(font
					(size 1.27 1.27)
					(thickness 0.15)
				)
				(justify left)
			)
		)
		(property "Value" "C_1u_0402"
			(at 167.64 109.22 0)
			(effects
				(font
					(size 1.27 1.27)
					(thickness 0.15)
				)
				(justify left bottom)
				(hide yes)
			)
		)
		(property "Footprint" "antmicro-footprints:C_0402_1005Metric"
			(at 170.18 109.22 0)
			(effects
				(font
					(size 1.27 1.27)
					(thickness 0.15)
				)
				(justify left bottom)
				(hide yes)
			)
		)
		(property "Datasheet" "https://product.tdk.com/en/search/capacitor/ceramic/mlcc/info?part_no=C1005X6S1A105K050BC"
			(at 172.72 109.22 0)
			(effects
				(font
					(size 1.27 1.27)
					(thickness 0.15)
				)
				(justify left bottom)
				(hide yes)
			)
		)
		(property "Description" "SMD Multilayer Ceramic Capacitor, 1 µF, 10 V, 0402 [1005 Metric], ± 10%, X6S, C"
			(at 157.48 129.54 0)
			(effects
				(font
					(size 1.27 1.27)
				)
				(hide yes)
			)
		)
		(property "MPN" "C1005X6S1A105K050BC"
			(at 175.26 109.22 0)
			(effects
				(font
					(size 1.27 1.27)
					(thickness 0.15)
				)
				(justify left bottom)
				(hide yes)
			)
		)
		(property "Manufacturer" "TDK"
			(at 177.8 109.22 0)
			(effects
				(font
					(size 1.27 1.27)
					(thickness 0.15)
				)
				(justify left bottom)
				(hide yes)
			)
		)
		(property "License" "Apache-2.0"
			(at 180.34 109.22 0)
			(effects
				(font
					(size 1.27 1.27)
					(thickness 0.15)
				)
				(justify left bottom)
				(hide yes)
			)
		)
		(property "Val" "1u"
			(at 154.94 128.2636 90)
			(effects
				(font
					(size 1.27 1.27)
					(thickness 0.15)
				)
				(justify left)
			)
		)
		(property "Voltage" ""
			(at 185.42 109.22 0)
			(effects
				(font
					(size 1.27 1.27)
				)
				(justify left bottom)
				(hide yes)
			)
		)
		(property "Dielectric" ""
			(at 187.96 109.22 0)
			(effects
				(font
					(size 1.27 1.27)
				)
				(justify left bottom)
				(hide yes)
			)
		)
		(property "Author" "Antmicro"
			(at 182.88 109.22 0)
			(effects
				(font
					(size 1.27 1.27)
					(thickness 0.15)
				)
				(justify left bottom)
				(hide yes)
			)
		)
		(pin "1"
		)
		(pin "2"
		)
		(instances
			(project "thunderbolt-to-10gbe-adapter"
				(path ""
					(reference "C66")
					(unit 1)
				)
			)
		)
	)
	(symbol
		(lib_id "antmicroLEDIndicationDiscrete:LED_G_0603_KP-1608CGCK")
		(at 254 201.93 90)
		(unit 1)
		(exclude_from_sim no)
		(in_bom yes)
		(on_board yes)
		(dnp no)
		(fields_autoplaced yes)
		(property "Reference" "D5"
			(at 256.54 198.12 90)
			(effects
				(font
					(size 1.27 1.27)
					(thickness 0.15)
				)
				(justify right)
			)
		)
		(property "Value" "LED_G_0603_KP-1608CGCK"
			(at 250.19 196.8501 90)
			(effects
				(font
					(size 1.27 1.27)
					(thickness 0.15)
				)
				(justify left)
				(hide yes)
			)
		)
		(property "Footprint" "antmicro-footprints:LED_0603_1608Metric_G"
			(at 264.16 179.07 0)
			(effects
				(font
					(size 1.27 1.27)
					(thickness 0.15)
				)
				(justify left bottom)
				(hide yes)
			)
		)
		(property "Datasheet" "http://www.kingbright.com/attachments/file/psearch//000/00/00/KP-1608CGCK(Ver.23B).pdf"
			(at 266.7 179.07 0)
			(effects
				(font
					(size 1.27 1.27)
					(thickness 0.15)
				)
				(justify left bottom)
				(hide yes)
			)
		)
		(property "Description" "LED, Green, SMD, 0603, 20 mA, 2.1 V, 570 nm"
			(at 254 201.93 0)
			(effects
				(font
					(size 1.27 1.27)
				)
				(hide yes)
			)
		)
		(property "MPN" "KP-1608CGCK"
			(at 269.24 179.07 0)
			(effects
				(font
					(size 1.27 1.27)
					(thickness 0.15)
				)
				(justify left bottom)
				(hide yes)
			)
		)
		(property "Manufacturer" "Kingbright"
			(at 271.78 179.07 0)
			(effects
				(font
					(size 1.27 1.27)
					(thickness 0.15)
				)
				(justify left bottom)
				(hide yes)
			)
		)
		(property "License" "Apache-2.0"
			(at 276.86 179.07 0)
			(effects
				(font
					(size 1.27 1.27)
					(thickness 0.15)
				)
				(justify left bottom)
				(hide yes)
			)
		)
		(property "Author" "Antmicro"
			(at 274.32 179.07 0)
			(effects
				(font
					(size 1.27 1.27)
					(thickness 0.15)
				)
				(justify left bottom)
				(hide yes)
			)
		)
		(property "Color" "Green"
			(at 256.54 200.66 90)
			(effects
				(font
					(size 1.27 1.27)
				)
				(justify right)
			)
		)
		(pin "1"
		)
		(pin "2"
		)
		(instances
			(project "thunderbolt-to-10gbe-adapter"
				(path ""
					(reference "D5")
					(unit 1)
				)
			)
		)
	)
	(symbol
		(lib_id "antmicroResistors0402:R_1k_0402")
		(at 275.59 148.59 90)
		(unit 1)
		(exclude_from_sim no)
		(in_bom yes)
		(on_board yes)
		(dnp no)
		(fields_autoplaced yes)
		(property "Reference" "R77"
			(at 273.05 144.78 90)
			(effects
				(font
					(size 1.27 1.27)
					(thickness 0.15)
				)
				(justify left)
			)
		)
		(property "Value" "R_1k_0402"
			(at 288.29 128.27 0)
			(effects
				(font
					(size 1.27 1.27)
					(thickness 0.15)
				)
				(justify left bottom)
				(hide yes)
			)
		)
		(property "Footprint" "antmicro-footprints:R_0402_1005Metric"
			(at 290.83 128.27 0)
			(effects
				(font
					(size 1.27 1.27)
					(thickness 0.15)
				)
				(justify left bottom)
				(hide yes)
			)
		)
		(property "Datasheet" "https://www.bourns.com/docs/product-datasheets/cr.pdf"
			(at 293.37 128.27 0)
			(effects
				(font
					(size 1.27 1.27)
					(thickness 0.15)
				)
				(justify left bottom)
				(hide yes)
			)
		)
		(property "Description" "SMD Chip Resistor, 1 kohm, ± 1%, 63 mW, 0402 [1005 Metric], Thick Film, General Purpose"
			(at 275.59 148.59 0)
			(effects
				(font
					(size 1.27 1.27)
				)
				(hide yes)
			)
		)
		(property "MPN" "CR0402-FX-1001GLF"
			(at 295.91 128.27 0)
			(effects
				(font
					(size 1.27 1.27)
					(thickness 0.15)
				)
				(justify left bottom)
				(hide yes)
			)
		)
		(property "Manufacturer" "Bourns"
			(at 298.45 128.27 0)
			(effects
				(font
					(size 1.27 1.27)
					(thickness 0.15)
				)
				(justify left bottom)
				(hide yes)
			)
		)
		(property "License" "Apache-2.0"
			(at 300.99 128.27 0)
			(effects
				(font
					(size 1.27 1.27)
					(thickness 0.15)
				)
				(justify left bottom)
				(hide yes)
			)
		)
		(property "Author" "Antmicro"
			(at 303.53 128.27 0)
			(effects
				(font
					(size 1.27 1.27)
					(thickness 0.15)
				)
				(justify left bottom)
				(hide yes)
			)
		)
		(property "Val" "1k"
			(at 273.05 147.32 90)
			(effects
				(font
					(size 1.27 1.27)
					(thickness 0.15)
				)
				(justify left)
			)
		)
		(property "Tolerance" "1%"
			(at 285.75 128.27 0)
			(effects
				(font
					(size 1.27 1.27)
				)
				(justify left bottom)
				(hide yes)
			)
		)
		(pin "1"
		)
		(pin "2"
		)
		(instances
			(project "thunderbolt-to-10gbe-adapter"
				(path ""
					(reference "R77")
					(unit 1)
				)
			)
		)
	)
	(symbol
		(lib_id "antmicroCapacitors0402:C_1u_0402")
		(at 157.48 93.98 90)
		(unit 1)
		(exclude_from_sim no)
		(in_bom yes)
		(on_board yes)
		(dnp no)
		(property "Reference" "C64"
			(at 158.115 89.535 90)
			(effects
				(font
					(size 1.27 1.27)
					(thickness 0.15)
				)
				(justify right)
			)
		)
		(property "Value" "C_1u_0402"
			(at 167.64 73.66 0)
			(effects
				(font
					(size 1.27 1.27)
					(thickness 0.15)
				)
				(justify left bottom)
				(hide yes)
			)
		)
		(property "Footprint" "antmicro-footprints:C_0402_1005Metric"
			(at 170.18 73.66 0)
			(effects
				(font
					(size 1.27 1.27)
					(thickness 0.15)
				)
				(justify left bottom)
				(hide yes)
			)
		)
		(property "Datasheet" "https://product.tdk.com/en/search/capacitor/ceramic/mlcc/info?part_no=C1005X6S1A105K050BC"
			(at 172.72 73.66 0)
			(effects
				(font
					(size 1.27 1.27)
					(thickness 0.15)
				)
				(justify left bottom)
				(hide yes)
			)
		)
		(property "Description" "SMD Multilayer Ceramic Capacitor, 1 µF, 10 V, 0402 [1005 Metric], ± 10%, X6S, C"
			(at 157.48 93.98 0)
			(effects
				(font
					(size 1.27 1.27)
				)
				(hide yes)
			)
		)
		(property "MPN" "C1005X6S1A105K050BC"
			(at 175.26 73.66 0)
			(effects
				(font
					(size 1.27 1.27)
					(thickness 0.15)
				)
				(justify left bottom)
				(hide yes)
			)
		)
		(property "Manufacturer" "TDK"
			(at 177.8 73.66 0)
			(effects
				(font
					(size 1.27 1.27)
					(thickness 0.15)
				)
				(justify left bottom)
				(hide yes)
			)
		)
		(property "License" "Apache-2.0"
			(at 180.34 73.66 0)
			(effects
				(font
					(size 1.27 1.27)
					(thickness 0.15)
				)
				(justify left bottom)
				(hide yes)
			)
		)
		(property "Val" "1u"
			(at 158.115 93.345 90)
			(effects
				(font
					(size 1.27 1.27)
					(thickness 0.15)
				)
				(justify right)
			)
		)
		(property "Voltage" ""
			(at 185.42 73.66 0)
			(effects
				(font
					(size 1.27 1.27)
				)
				(justify left bottom)
				(hide yes)
			)
		)
		(property "Dielectric" ""
			(at 187.96 73.66 0)
			(effects
				(font
					(size 1.27 1.27)
				)
				(justify left bottom)
				(hide yes)
			)
		)
		(property "Author" "Antmicro"
			(at 182.88 73.66 0)
			(effects
				(font
					(size 1.27 1.27)
					(thickness 0.15)
				)
				(justify left bottom)
				(hide yes)
			)
		)
		(pin "1"
		)
		(pin "2"
		)
		(instances
			(project "thunderbolt-to-10gbe-adapter"
				(path ""
					(reference "C64")
					(unit 1)
				)
			)
		)
	)
	(symbol
		(lib_id "antmicropower:GND")
		(at 240.03 148.59 0)
		(unit 1)
		(exclude_from_sim no)
		(in_bom yes)
		(on_board yes)
		(dnp no)
		(property "Reference" "#PWR0117"
			(at 240.03 154.94 0)
			(effects
				(font
					(size 1.27 1.27)
				)
				(hide yes)
			)
		)
		(property "Value" "GND"
			(at 240.03 152.4 0)
			(effects
				(font
					(size 1.27 1.27)
				)
			)
		)
		(property "Footprint" ""
			(at 240.03 148.59 0)
			(effects
				(font
					(size 1.27 1.27)
				)
				(hide yes)
			)
		)
		(property "Datasheet" ""
			(at 240.03 148.59 0)
			(effects
				(font
					(size 1.27 1.27)
				)
				(hide yes)
			)
		)
		(property "Description" ""
			(at 240.03 148.59 0)
			(effects
				(font
					(size 1.27 1.27)
				)
				(hide yes)
			)
		)
		(property "Author" "Antmicro"
			(at 248.92 156.21 0)
			(effects
				(font
					(size 1.27 1.27)
					(thickness 0.15)
				)
				(justify left bottom)
				(hide yes)
			)
		)
		(property "License" "Apache-2.0"
			(at 248.92 158.75 0)
			(effects
				(font
					(size 1.27 1.27)
					(thickness 0.15)
				)
				(justify left bottom)
				(hide yes)
			)
		)
		(pin "1"
		)
		(instances
			(project "thunderbolt-to-10gbe-adapter"
				(path ""
					(reference "#PWR0117")
					(unit 1)
				)
			)
		)
	)
	(symbol
		(lib_id "antmicroCapacitors0402:C_1u_0402")
		(at 147.32 93.98 90)
		(unit 1)
		(exclude_from_sim no)
		(in_bom yes)
		(on_board yes)
		(dnp no)
		(property "Reference" "C56"
			(at 147.955 89.535 90)
			(effects
				(font
					(size 1.27 1.27)
					(thickness 0.15)
				)
				(justify right)
			)
		)
		(property "Value" "C_1u_0402"
			(at 157.48 73.66 0)
			(effects
				(font
					(size 1.27 1.27)
					(thickness 0.15)
				)
				(justify left bottom)
				(hide yes)
			)
		)
		(property "Footprint" "antmicro-footprints:C_0402_1005Metric"
			(at 160.02 73.66 0)
			(effects
				(font
					(size 1.27 1.27)
					(thickness 0.15)
				)
				(justify left bottom)
				(hide yes)
			)
		)
		(property "Datasheet" "https://product.tdk.com/en/search/capacitor/ceramic/mlcc/info?part_no=C1005X6S1A105K050BC"
			(at 162.56 73.66 0)
			(effects
				(font
					(size 1.27 1.27)
					(thickness 0.15)
				)
				(justify left bottom)
				(hide yes)
			)
		)
		(property "Description" "SMD Multilayer Ceramic Capacitor, 1 µF, 10 V, 0402 [1005 Metric], ± 10%, X6S, C"
			(at 147.32 93.98 0)
			(effects
				(font
					(size 1.27 1.27)
				)
				(hide yes)
			)
		)
		(property "MPN" "C1005X6S1A105K050BC"
			(at 165.1 73.66 0)
			(effects
				(font
					(size 1.27 1.27)
					(thickness 0.15)
				)
				(justify left bottom)
				(hide yes)
			)
		)
		(property "Manufacturer" "TDK"
			(at 167.64 73.66 0)
			(effects
				(font
					(size 1.27 1.27)
					(thickness 0.15)
				)
				(justify left bottom)
				(hide yes)
			)
		)
		(property "License" "Apache-2.0"
			(at 170.18 73.66 0)
			(effects
				(font
					(size 1.27 1.27)
					(thickness 0.15)
				)
				(justify left bottom)
				(hide yes)
			)
		)
		(property "Val" "1u"
			(at 147.955 93.345 90)
			(effects
				(font
					(size 1.27 1.27)
					(thickness 0.15)
				)
				(justify right)
			)
		)
		(property "Voltage" ""
			(at 175.26 73.66 0)
			(effects
				(font
					(size 1.27 1.27)
				)
				(justify left bottom)
				(hide yes)
			)
		)
		(property "Dielectric" ""
			(at 177.8 73.66 0)
			(effects
				(font
					(size 1.27 1.27)
				)
				(justify left bottom)
				(hide yes)
			)
		)
		(property "Author" "Antmicro"
			(at 172.72 73.66 0)
			(effects
				(font
					(size 1.27 1.27)
					(thickness 0.15)
				)
				(justify left bottom)
				(hide yes)
			)
		)
		(pin "1"
		)
		(pin "2"
		)
		(instances
			(project "thunderbolt-to-10gbe-adapter"
				(path ""
					(reference "C56")
					(unit 1)
				)
			)
		)
	)
	(symbol
		(lib_id "antmicroCapacitors0402:C_1u_0402")
		(at 137.16 93.98 90)
		(unit 1)
		(exclude_from_sim no)
		(in_bom yes)
		(on_board yes)
		(dnp no)
		(property "Reference" "C52"
			(at 137.795 89.535 90)
			(effects
				(font
					(size 1.27 1.27)
					(thickness 0.15)
				)
				(justify right)
			)
		)
		(property "Value" "C_1u_0402"
			(at 147.32 73.66 0)
			(effects
				(font
					(size 1.27 1.27)
					(thickness 0.15)
				)
				(justify left bottom)
				(hide yes)
			)
		)
		(property "Footprint" "antmicro-footprints:C_0402_1005Metric"
			(at 149.86 73.66 0)
			(effects
				(font
					(size 1.27 1.27)
					(thickness 0.15)
				)
				(justify left bottom)
				(hide yes)
			)
		)
		(property "Datasheet" "https://product.tdk.com/en/search/capacitor/ceramic/mlcc/info?part_no=C1005X6S1A105K050BC"
			(at 152.4 73.66 0)
			(effects
				(font
					(size 1.27 1.27)
					(thickness 0.15)
				)
				(justify left bottom)
				(hide yes)
			)
		)
		(property "Description" "SMD Multilayer Ceramic Capacitor, 1 µF, 10 V, 0402 [1005 Metric], ± 10%, X6S, C"
			(at 137.16 93.98 0)
			(effects
				(font
					(size 1.27 1.27)
				)
				(hide yes)
			)
		)
		(property "MPN" "C1005X6S1A105K050BC"
			(at 154.94 73.66 0)
			(effects
				(font
					(size 1.27 1.27)
					(thickness 0.15)
				)
				(justify left bottom)
				(hide yes)
			)
		)
		(property "Manufacturer" "TDK"
			(at 157.48 73.66 0)
			(effects
				(font
					(size 1.27 1.27)
					(thickness 0.15)
				)
				(justify left bottom)
				(hide yes)
			)
		)
		(property "License" "Apache-2.0"
			(at 160.02 73.66 0)
			(effects
				(font
					(size 1.27 1.27)
					(thickness 0.15)
				)
				(justify left bottom)
				(hide yes)
			)
		)
		(property "Val" "1u"
			(at 137.795 93.345 90)
			(effects
				(font
					(size 1.27 1.27)
					(thickness 0.15)
				)
				(justify right)
			)
		)
		(property "Voltage" ""
			(at 165.1 73.66 0)
			(effects
				(font
					(size 1.27 1.27)
				)
				(justify left bottom)
				(hide yes)
			)
		)
		(property "Dielectric" ""
			(at 167.64 73.66 0)
			(effects
				(font
					(size 1.27 1.27)
				)
				(justify left bottom)
				(hide yes)
			)
		)
		(property "Author" "Antmicro"
			(at 162.56 73.66 0)
			(effects
				(font
					(size 1.27 1.27)
					(thickness 0.15)
				)
				(justify left bottom)
				(hide yes)
			)
		)
		(pin "1"
		)
		(pin "2"
		)
		(instances
			(project "thunderbolt-to-10gbe-adapter"
				(path ""
					(reference "C52")
					(unit 1)
				)
			)
		)
	)
	(symbol
		(lib_id "antmicropower:GND")
		(at 252.73 113.03 0)
		(unit 1)
		(exclude_from_sim no)
		(in_bom yes)
		(on_board yes)
		(dnp no)
		(property "Reference" "#PWR0126"
			(at 252.73 119.38 0)
			(effects
				(font
					(size 1.27 1.27)
				)
				(hide yes)
			)
		)
		(property "Value" "GND"
			(at 252.73 116.84 0)
			(effects
				(font
					(size 1.27 1.27)
				)
			)
		)
		(property "Footprint" ""
			(at 252.73 113.03 0)
			(effects
				(font
					(size 1.27 1.27)
				)
				(hide yes)
			)
		)
		(property "Datasheet" ""
			(at 252.73 113.03 0)
			(effects
				(font
					(size 1.27 1.27)
				)
				(hide yes)
			)
		)
		(property "Description" ""
			(at 252.73 113.03 0)
			(effects
				(font
					(size 1.27 1.27)
				)
				(hide yes)
			)
		)
		(property "Author" "Antmicro"
			(at 261.62 120.65 0)
			(effects
				(font
					(size 1.27 1.27)
					(thickness 0.15)
				)
				(justify left bottom)
				(hide yes)
			)
		)
		(property "License" "Apache-2.0"
			(at 261.62 123.19 0)
			(effects
				(font
					(size 1.27 1.27)
					(thickness 0.15)
				)
				(justify left bottom)
				(hide yes)
			)
		)
		(pin "1"
		)
		(instances
			(project "thunderbolt-to-10gbe-adapter"
				(path ""
					(reference "#PWR0126")
					(unit 1)
				)
			)
		)
	)
	(symbol
		(lib_id "antmicroCapacitors0402:C_1u_0402")
		(at 161.29 167.64 270)
		(mirror x)
		(unit 1)
		(exclude_from_sim no)
		(in_bom yes)
		(on_board yes)
		(dnp no)
		(property "Reference" "C68"
			(at 160.655 163.195 90)
			(effects
				(font
					(size 1.27 1.27)
					(thickness 0.15)
				)
				(justify right)
			)
		)
		(property "Value" "C_1u_0402"
			(at 151.13 147.32 0)
			(effects
				(font
					(size 1.27 1.27)
					(thickness 0.15)
				)
				(justify left bottom)
				(hide yes)
			)
		)
		(property "Footprint" "antmicro-footprints:C_0402_1005Metric"
			(at 148.59 147.32 0)
			(effects
				(font
					(size 1.27 1.27)
					(thickness 0.15)
				)
				(justify left bottom)
				(hide yes)
			)
		)
		(property "Datasheet" "https://product.tdk.com/en/search/capacitor/ceramic/mlcc/info?part_no=C1005X6S1A105K050BC"
			(at 146.05 147.32 0)
			(effects
				(font
					(size 1.27 1.27)
					(thickness 0.15)
				)
				(justify left bottom)
				(hide yes)
			)
		)
		(property "Description" "SMD Multilayer Ceramic Capacitor, 1 µF, 10 V, 0402 [1005 Metric], ± 10%, X6S, C"
			(at 161.29 167.64 0)
			(effects
				(font
					(size 1.27 1.27)
				)
				(hide yes)
			)
		)
		(property "MPN" "C1005X6S1A105K050BC"
			(at 143.51 147.32 0)
			(effects
				(font
					(size 1.27 1.27)
					(thickness 0.15)
				)
				(justify left bottom)
				(hide yes)
			)
		)
		(property "Manufacturer" "TDK"
			(at 140.97 147.32 0)
			(effects
				(font
					(size 1.27 1.27)
					(thickness 0.15)
				)
				(justify left bottom)
				(hide yes)
			)
		)
		(property "License" "Apache-2.0"
			(at 138.43 147.32 0)
			(effects
				(font
					(size 1.27 1.27)
					(thickness 0.15)
				)
				(justify left bottom)
				(hide yes)
			)
		)
		(property "Val" "1u"
			(at 160.655 167.005 90)
			(effects
				(font
					(size 1.27 1.27)
					(thickness 0.15)
				)
				(justify right)
			)
		)
		(property "Voltage" ""
			(at 133.35 147.32 0)
			(effects
				(font
					(size 1.27 1.27)
				)
				(justify left bottom)
				(hide yes)
			)
		)
		(property "Dielectric" ""
			(at 130.81 147.32 0)
			(effects
				(font
					(size 1.27 1.27)
				)
				(justify left bottom)
				(hide yes)
			)
		)
		(property "Author" "Antmicro"
			(at 135.89 147.32 0)
			(effects
				(font
					(size 1.27 1.27)
					(thickness 0.15)
				)
				(justify left bottom)
				(hide yes)
			)
		)
		(pin "1"
		)
		(pin "2"
		)
		(instances
			(project "thunderbolt-to-10gbe-adapter"
				(path ""
					(reference "C68")
					(unit 1)
				)
			)
		)
	)
	(symbol
		(lib_id "antmicroCapacitors0402:C_1u_0402")
		(at 147.32 111.76 90)
		(unit 1)
		(exclude_from_sim no)
		(in_bom yes)
		(on_board yes)
		(dnp no)
		(property "Reference" "C57"
			(at 147.955 107.315 90)
			(effects
				(font
					(size 1.27 1.27)
					(thickness 0.15)
				)
				(justify right)
			)
		)
		(property "Value" "C_1u_0402"
			(at 157.48 91.44 0)
			(effects
				(font
					(size 1.27 1.27)
					(thickness 0.15)
				)
				(justify left bottom)
				(hide yes)
			)
		)
		(property "Footprint" "antmicro-footprints:C_0402_1005Metric"
			(at 160.02 91.44 0)
			(effects
				(font
					(size 1.27 1.27)
					(thickness 0.15)
				)
				(justify left bottom)
				(hide yes)
			)
		)
		(property "Datasheet" "https://product.tdk.com/en/search/capacitor/ceramic/mlcc/info?part_no=C1005X6S1A105K050BC"
			(at 162.56 91.44 0)
			(effects
				(font
					(size 1.27 1.27)
					(thickness 0.15)
				)
				(justify left bottom)
				(hide yes)
			)
		)
		(property "Description" "SMD Multilayer Ceramic Capacitor, 1 µF, 10 V, 0402 [1005 Metric], ± 10%, X6S, C"
			(at 147.32 111.76 0)
			(effects
				(font
					(size 1.27 1.27)
				)
				(hide yes)
			)
		)
		(property "MPN" "C1005X6S1A105K050BC"
			(at 165.1 91.44 0)
			(effects
				(font
					(size 1.27 1.27)
					(thickness 0.15)
				)
				(justify left bottom)
				(hide yes)
			)
		)
		(property "Manufacturer" "TDK"
			(at 167.64 91.44 0)
			(effects
				(font
					(size 1.27 1.27)
					(thickness 0.15)
				)
				(justify left bottom)
				(hide yes)
			)
		)
		(property "License" "Apache-2.0"
			(at 170.18 91.44 0)
			(effects
				(font
					(size 1.27 1.27)
					(thickness 0.15)
				)
				(justify left bottom)
				(hide yes)
			)
		)
		(property "Val" "1u"
			(at 147.955 111.125 90)
			(effects
				(font
					(size 1.27 1.27)
					(thickness 0.15)
				)
				(justify right)
			)
		)
		(property "Voltage" ""
			(at 175.26 91.44 0)
			(effects
				(font
					(size 1.27 1.27)
				)
				(justify left bottom)
				(hide yes)
			)
		)
		(property "Dielectric" ""
			(at 177.8 91.44 0)
			(effects
				(font
					(size 1.27 1.27)
				)
				(justify left bottom)
				(hide yes)
			)
		)
		(property "Author" "Antmicro"
			(at 172.72 91.44 0)
			(effects
				(font
					(size 1.27 1.27)
					(thickness 0.15)
				)
				(justify left bottom)
				(hide yes)
			)
		)
		(pin "1"
		)
		(pin "2"
		)
		(instances
			(project "thunderbolt-to-10gbe-adapter"
				(path ""
					(reference "C57")
					(unit 1)
				)
			)
		)
	)
	(symbol
		(lib_id "antmicropower:GND")
		(at 252.73 148.59 0)
		(unit 1)
		(exclude_from_sim no)
		(in_bom yes)
		(on_board yes)
		(dnp no)
		(property "Reference" "#PWR0128"
			(at 252.73 154.94 0)
			(effects
				(font
					(size 1.27 1.27)
				)
				(hide yes)
			)
		)
		(property "Value" "GND"
			(at 252.73 152.4 0)
			(effects
				(font
					(size 1.27 1.27)
				)
			)
		)
		(property "Footprint" ""
			(at 252.73 148.59 0)
			(effects
				(font
					(size 1.27 1.27)
				)
				(hide yes)
			)
		)
		(property "Datasheet" ""
			(at 252.73 148.59 0)
			(effects
				(font
					(size 1.27 1.27)
				)
				(hide yes)
			)
		)
		(property "Description" ""
			(at 252.73 148.59 0)
			(effects
				(font
					(size 1.27 1.27)
				)
				(hide yes)
			)
		)
		(property "Author" "Antmicro"
			(at 261.62 156.21 0)
			(effects
				(font
					(size 1.27 1.27)
					(thickness 0.15)
				)
				(justify left bottom)
				(hide yes)
			)
		)
		(property "License" "Apache-2.0"
			(at 261.62 158.75 0)
			(effects
				(font
					(size 1.27 1.27)
					(thickness 0.15)
				)
				(justify left bottom)
				(hide yes)
			)
		)
		(pin "1"
		)
		(instances
			(project "thunderbolt-to-10gbe-adapter"
				(path ""
					(reference "#PWR0128")
					(unit 1)
				)
			)
		)
	)
	(symbol
		(lib_id "antmicroCapacitors0402:C_1u_0402")
		(at 157.48 147.32 90)
		(unit 1)
		(exclude_from_sim no)
		(in_bom yes)
		(on_board yes)
		(dnp no)
		(property "Reference" "C67"
			(at 158.115 142.875 90)
			(effects
				(font
					(size 1.27 1.27)
					(thickness 0.15)
				)
				(justify right)
			)
		)
		(property "Value" "C_1u_0402"
			(at 167.64 127 0)
			(effects
				(font
					(size 1.27 1.27)
					(thickness 0.15)
				)
				(justify left bottom)
				(hide yes)
			)
		)
		(property "Footprint" "antmicro-footprints:C_0402_1005Metric"
			(at 170.18 127 0)
			(effects
				(font
					(size 1.27 1.27)
					(thickness 0.15)
				)
				(justify left bottom)
				(hide yes)
			)
		)
		(property "Datasheet" "https://product.tdk.com/en/search/capacitor/ceramic/mlcc/info?part_no=C1005X6S1A105K050BC"
			(at 172.72 127 0)
			(effects
				(font
					(size 1.27 1.27)
					(thickness 0.15)
				)
				(justify left bottom)
				(hide yes)
			)
		)
		(property "Description" "SMD Multilayer Ceramic Capacitor, 1 µF, 10 V, 0402 [1005 Metric], ± 10%, X6S, C"
			(at 157.48 147.32 0)
			(effects
				(font
					(size 1.27 1.27)
				)
				(hide yes)
			)
		)
		(property "MPN" "C1005X6S1A105K050BC"
			(at 175.26 127 0)
			(effects
				(font
					(size 1.27 1.27)
					(thickness 0.15)
				)
				(justify left bottom)
				(hide yes)
			)
		)
		(property "Manufacturer" "TDK"
			(at 177.8 127 0)
			(effects
				(font
					(size 1.27 1.27)
					(thickness 0.15)
				)
				(justify left bottom)
				(hide yes)
			)
		)
		(property "License" "Apache-2.0"
			(at 180.34 127 0)
			(effects
				(font
					(size 1.27 1.27)
					(thickness 0.15)
				)
				(justify left bottom)
				(hide yes)
			)
		)
		(property "Val" "1u"
			(at 158.115 146.685 90)
			(effects
				(font
					(size 1.27 1.27)
					(thickness 0.15)
				)
				(justify right)
			)
		)
		(property "Voltage" ""
			(at 185.42 127 0)
			(effects
				(font
					(size 1.27 1.27)
				)
				(justify left bottom)
				(hide yes)
			)
		)
		(property "Dielectric" ""
			(at 187.96 127 0)
			(effects
				(font
					(size 1.27 1.27)
				)
				(justify left bottom)
				(hide yes)
			)
		)
		(property "Author" "Antmicro"
			(at 182.88 127 0)
			(effects
				(font
					(size 1.27 1.27)
					(thickness 0.15)
				)
				(justify left bottom)
				(hide yes)
			)
		)
		(pin "1"
		)
		(pin "2"
		)
		(instances
			(project "thunderbolt-to-10gbe-adapter"
				(path ""
					(reference "C67")
					(unit 1)
				)
			)
		)
	)
	(symbol
		(lib_id "antmicropower:GND")
		(at 137.16 96.52 0)
		(unit 1)
		(exclude_from_sim no)
		(in_bom yes)
		(on_board yes)
		(dnp no)
		(property "Reference" "#PWR080"
			(at 137.16 102.87 0)
			(effects
				(font
					(size 1.27 1.27)
				)
				(hide yes)
			)
		)
		(property "Value" "GND"
			(at 137.16 100.33 0)
			(effects
				(font
					(size 1.27 1.27)
				)
			)
		)
		(property "Footprint" ""
			(at 137.16 96.52 0)
			(effects
				(font
					(size 1.27 1.27)
				)
				(hide yes)
			)
		)
		(property "Datasheet" ""
			(at 137.16 96.52 0)
			(effects
				(font
					(size 1.27 1.27)
				)
				(hide yes)
			)
		)
		(property "Description" ""
			(at 137.16 96.52 0)
			(effects
				(font
					(size 1.27 1.27)
				)
				(hide yes)
			)
		)
		(property "Author" "Antmicro"
			(at 146.05 104.14 0)
			(effects
				(font
					(size 1.27 1.27)
					(thickness 0.15)
				)
				(justify left bottom)
				(hide yes)
			)
		)
		(property "License" "Apache-2.0"
			(at 146.05 106.68 0)
			(effects
				(font
					(size 1.27 1.27)
					(thickness 0.15)
				)
				(justify left bottom)
				(hide yes)
			)
		)
		(pin "1"
		)
		(instances
			(project "thunderbolt-to-10gbe-adapter"
				(path ""
					(reference "#PWR080")
					(unit 1)
				)
			)
		)
	)
	(symbol
		(lib_id "antmicroCapacitorspol:C_Pol_330u_6.3V_KEMET-T520-B")
		(at 138.43 217.17 270)
		(unit 1)
		(exclude_from_sim no)
		(in_bom yes)
		(on_board yes)
		(dnp no)
		(property "Reference" "C53"
			(at 135.89 217.9066 90)
			(effects
				(font
					(size 1.27 1.27)
					(thickness 0.15)
				)
				(justify right)
			)
		)
		(property "Value" "C_Pol_330u_6.3V_KEMET-T520-B"
			(at 135.89 231.14 0)
			(effects
				(font
					(size 1.27 1.27)
					(thickness 0.15)
				)
				(justify left bottom)
				(hide yes)
			)
		)
		(property "Footprint" "antmicro-footprints:C_Pol_EIA-B"
			(at 130.81 231.14 0)
			(effects
				(font
					(size 1.27 1.27)
					(thickness 0.15)
				)
				(justify left bottom)
				(hide yes)
			)
		)
		(property "Datasheet" "https://www.kemet.com/en/us/capacitors/product/T520B337M006ATE040.html"
			(at 128.27 231.14 0)
			(effects
				(font
					(size 1.27 1.27)
					(thickness 0.15)
				)
				(justify left bottom)
				(hide yes)
			)
		)
		(property "Description" "Tantalum Polymer Capacitor, KO-CAP®, 330 µF, ± 20%, 6.3 V, B, 0.04 ohm, 1411 [3528 Metric]"
			(at 138.43 217.17 0)
			(effects
				(font
					(size 1.27 1.27)
				)
				(hide yes)
			)
		)
		(property "Val" "330u"
			(at 135.89 220.4466 90)
			(effects
				(font
					(size 1.27 1.27)
					(thickness 0.15)
				)
				(justify right)
			)
		)
		(property "MPN" "T520B337M006ATE040"
			(at 125.73 231.14 0)
			(effects
				(font
					(size 1.27 1.27)
					(thickness 0.15)
				)
				(justify left bottom)
				(hide yes)
			)
		)
		(property "Manufacturer" "KEMET"
			(at 123.19 231.14 0)
			(effects
				(font
					(size 1.27 1.27)
					(thickness 0.15)
				)
				(justify left bottom)
				(hide yes)
			)
		)
		(property "License" "Apache-2.0"
			(at 120.65 231.14 0)
			(effects
				(font
					(size 1.27 1.27)
					(thickness 0.15)
				)
				(justify left bottom)
				(hide yes)
			)
		)
		(property "Author" "Antmicro"
			(at 118.11 231.14 0)
			(effects
				(font
					(size 1.27 1.27)
					(thickness 0.15)
				)
				(justify left bottom)
				(hide yes)
			)
		)
		(property "Voltage" "6.3V"
			(at 115.57 231.14 0)
			(effects
				(font
					(size 1.27 1.27)
				)
				(justify left bottom)
				(hide yes)
			)
		)
		(property "Dielectric" "template_dielectric"
			(at 113.03 231.14 0)
			(effects
				(font
					(size 1.27 1.27)
				)
				(justify left bottom)
				(hide yes)
			)
		)
		(pin "1"
		)
		(pin "2"
		)
		(instances
			(project "thunderbolt-to-10gbe-adapter"
				(path ""
					(reference "C53")
					(unit 1)
				)
			)
		)
	)
	(symbol
		(lib_id "antmicroInterfaceControllers:JHL6340SLLSQ")
		(at 167.64 85.09 0)
		(unit 1)
		(exclude_from_sim no)
		(in_bom yes)
		(on_board yes)
		(dnp no)
		(fields_autoplaced yes)
		(property "Reference" "U4"
			(at 194.945 76.835 0)
			(effects
				(font
					(size 1.27 1.27)
					(thickness 0.15)
				)
			)
		)
		(property "Value" "JHL6340SLLSQ"
			(at 238.76 87.63 0)
			(effects
				(font
					(size 1.27 1.27)
					(thickness 0.15)
				)
				(justify left bottom)
				(hide yes)
			)
		)
		(property "Footprint" "antmicro-footprints:JHL6340SLLSQ"
			(at 238.76 90.17 0)
			(effects
				(font
					(size 1.27 1.27)
					(thickness 0.15)
				)
				(justify left bottom)
				(hide yes)
			)
		)
		(property "Datasheet" "https://www.thunderbolttechnology.net/sites/default/files/18-241_ThunderboltController_Brief_HI.pdf"
			(at 238.76 92.71 0)
			(effects
				(font
					(size 1.27 1.27)
					(thickness 0.15)
				)
				(justify left bottom)
				(hide yes)
			)
		)
		(property "Description" "Thunderbolt™ 3 Controller, I/O"
			(at 167.64 85.09 0)
			(effects
				(font
					(size 1.27 1.27)
				)
				(hide yes)
			)
		)
		(property "Manufacturer" "Intel"
			(at 238.76 95.25 0)
			(effects
				(font
					(size 1.27 1.27)
					(thickness 0.15)
				)
				(justify left bottom)
				(hide yes)
			)
		)
		(property "MPN" "JHL6340SLLSQ"
			(at 194.945 79.375 0)
			(effects
				(font
					(size 1.27 1.27)
					(thickness 0.15)
				)
			)
		)
		(property "Author" "Antmicro"
			(at 238.76 100.33 0)
			(effects
				(font
					(size 1.27 1.27)
					(thickness 0.15)
				)
				(justify left bottom)
				(hide yes)
			)
		)
		(property "License" "Apache-2.0"
			(at 238.76 102.87 0)
			(effects
				(font
					(size 1.27 1.27)
					(thickness 0.15)
				)
				(justify left bottom)
				(hide yes)
			)
		)
		(pin "V5"
		)
		(pin "Y9"
		)
		(pin "AC5"
		)
		(pin "F12"
		)
		(pin "L13"
		)
		(pin "A13"
		)
		(pin "T23"
		)
		(pin "AA2"
		)
		(pin "L22"
		)
		(pin "R16"
		)
		(pin "N13"
		)
		(pin "D9"
		)
		(pin "T2"
		)
		(pin "R12"
		)
		(pin "U1"
		)
		(pin "R23"
		)
		(pin "J23"
		)
		(pin "T22"
		)
		(pin "L23"
		)
		(pin "B3"
		)
		(pin "V4"
		)
		(pin "N8"
		)
		(pin "AB11"
		)
		(pin "AB4"
		)
		(pin "M6"
		)
		(pin "K22"
		)
		(pin "R5"
		)
		(pin "L15"
		)
		(pin "F13"
		)
		(pin "L12"
		)
		(pin "H20"
		)
		(pin "V15"
		)
		(pin "V22"
		)
		(pin "V19"
		)
		(pin "P23"
		)
		(pin "M18"
		)
		(pin "A4"
		)
		(pin "A9"
		)
		(pin "M23"
		)
		(pin "Y8"
		)
		(pin "Y4"
		)
		(pin "N5"
		)
		(pin "T5"
		)
		(pin "W1"
		)
		(pin "Y11"
		)
		(pin "Y5"
		)
		(pin "B22"
		)
		(pin "B6"
		)
		(pin "V8"
		)
		(pin "V1"
		)
		(pin "A17"
		)
		(pin "Y2"
		)
		(pin "W2"
		)
		(pin "R22"
		)
		(pin "N6"
		)
		(pin "F16"
		)
		(pin "AB13"
		)
		(pin "H4"
		)
		(pin "F22"
		)
		(pin "R4"
		)
		(pin "F23"
		)
		(pin "W11"
		)
		(pin "D13"
		)
		(pin "AC10"
		)
		(pin "M9"
		)
		(pin "V2"
		)
		(pin "L19"
		)
		(pin "T18"
		)
		(pin "L20"
		)
		(pin "H8"
		)
		(pin "AB7"
		)
		(pin "Y23"
		)
		(pin "K1"
		)
		(pin "AC7"
		)
		(pin "H18"
		)
		(pin "C1"
		)
		(pin "N1"
		)
		(pin "AB5"
		)
		(pin "J5"
		)
		(pin "R15"
		)
		(pin "M13"
		)
		(pin "D1"
		)
		(pin "E20"
		)
		(pin "AC11"
		)
		(pin "A5"
		)
		(pin "AB15"
		)
		(pin "L8"
		)
		(pin "D6"
		)
		(pin "D19"
		)
		(pin "V6"
		)
		(pin "N19"
		)
		(pin "T11"
		)
		(pin "W8"
		)
		(pin "C22"
		)
		(pin "H19"
		)
		(pin "L11"
		)
		(pin "AC13"
		)
		(pin "D2"
		)
		(pin "K23"
		)
		(pin "L2"
		)
		(pin "A7"
		)
		(pin "H16"
		)
		(pin "Y16"
		)
		(pin "V12"
		)
		(pin "AB9"
		)
		(pin "M20"
		)
		(pin "N20"
		)
		(pin "R19"
		)
		(pin "U22"
		)
		(pin "AB21"
		)
		(pin "E4"
		)
		(pin "R6"
		)
		(pin "R20"
		)
		(pin "AC1"
		)
		(pin "G2"
		)
		(pin "M8"
		)
		(pin "M16"
		)
		(pin "V20"
		)
		(pin "F18"
		)
		(pin "AB3"
		)
		(pin "AA1"
		)
		(pin "D22"
		)
		(pin "V11"
		)
		(pin "T1"
		)
		(pin "V18"
		)
		(pin "B9"
		)
		(pin "J9"
		)
		(pin "M5"
		)
		(pin "H15"
		)
		(pin "M12"
		)
		(pin "M15"
		)
		(pin "AC9"
		)
		(pin "W23"
		)
		(pin "V9"
		)
		(pin "B8"
		)
		(pin "N16"
		)
		(pin "B14"
		)
		(pin "AC23"
		)
		(pin "W18"
		)
		(pin "M1"
		)
		(pin "N15"
		)
		(pin "AB17"
		)
		(pin "U23"
		)
		(pin "Y22"
		)
		(pin "L9"
		)
		(pin "T13"
		)
		(pin "F11"
		)
		(pin "N4"
		)
		(pin "F19"
		)
		(pin "W6"
		)
		(pin "F15"
		)
		(pin "B7"
		)
		(pin "Y1"
		)
		(pin "A6"
		)
		(pin "B2"
		)
		(pin "B4"
		)
		(pin "R13"
		)
		(pin "K2"
		)
		(pin "N18"
		)
		(pin "B13"
		)
		(pin "T19"
		)
		(pin "W22"
		)
		(pin "H23"
		)
		(pin "T4"
		)
		(pin "L18"
		)
		(pin "E19"
		)
		(pin "H2"
		)
		(pin "L1"
		)
		(pin "F20"
		)
		(pin "B23"
		)
		(pin "R8"
		)
		(pin "M22"
		)
		(pin "F2"
		)
		(pin "E18"
		)
		(pin "R2"
		)
		(pin "W4"
		)
		(pin "B5"
		)
		(pin "W19"
		)
		(pin "N22"
		)
		(pin "D5"
		)
		(pin "W20"
		)
		(pin "W12"
		)
		(pin "B11"
		)
		(pin "R11"
		)
		(pin "E2"
		)
		(pin "D18"
		)
		(pin "T8"
		)
		(pin "L5"
		)
		(pin "M4"
		)
		(pin "T20"
		)
		(pin "A3"
		)
		(pin "AC3"
		)
		(pin "A19"
		)
		(pin "L16"
		)
		(pin "F4"
		)
		(pin "T12"
		)
		(pin "Y18"
		)
		(pin "T16"
		)
		(pin "AB19"
		)
		(pin "B12"
		)
		(pin "E23"
		)
		(pin "E1"
		)
		(pin "T6"
		)
		(pin "Y19"
		)
		(pin "T15"
		)
		(pin "P22"
		)
		(pin "AB16"
		)
		(pin "AC4"
		)
		(pin "D15"
		)
		(pin "G1"
		)
		(pin "A8"
		)
		(pin "Y12"
		)
		(pin "J4"
		)
		(pin "J1"
		)
		(pin "E22"
		)
		(pin "D20"
		)
		(pin "M2"
		)
		(pin "V23"
		)
		(pin "AB10"
		)
		(pin "AB2"
		)
		(pin "AC15"
		)
		(pin "D23"
		)
		(pin "A23"
		)
		(pin "C23"
		)
		(pin "J2"
		)
		(pin "A21"
		)
		(pin "F1"
		)
		(pin "H5"
		)
		(pin "N11"
		)
		(pin "B20"
		)
		(pin "H22"
		)
		(pin "AA23"
		)
		(pin "E13"
		)
		(pin "J12"
		)
		(pin "W9"
		)
		(pin "H9"
		)
		(pin "B19"
		)
		(pin "AB8"
		)
		(pin "AB22"
		)
		(pin "AB6"
		)
		(pin "AB20"
		)
		(pin "AC2"
		)
		(pin "E9"
		)
		(pin "J11"
		)
		(pin "L4"
		)
		(pin "J8"
		)
		(pin "AC22"
		)
		(pin "J13"
		)
		(pin "N12"
		)
		(pin "J15"
		)
		(pin "B18"
		)
		(pin "Y15"
		)
		(pin "U2"
		)
		(pin "AC12"
		)
		(pin "D16"
		)
		(pin "AB14"
		)
		(pin "AC6"
		)
		(pin "A14"
		)
		(pin "V13"
		)
		(pin "G22"
		)
		(pin "Y13"
		)
		(pin "B16"
		)
		(pin "AB18"
		)
		(pin "B17"
		)
		(pin "A20"
		)
		(pin "AB12"
		)
		(pin "R1"
		)
		(pin "AC20"
		)
		(pin "H12"
		)
		(pin "A2"
		)
		(pin "F5"
		)
		(pin "E6"
		)
		(pin "A10"
		)
		(pin "A12"
		)
		(pin "H11"
		)
		(pin "F9"
		)
		(pin "A1"
		)
		(pin "AB1"
		)
		(pin "E8"
		)
		(pin "A11"
		)
		(pin "L6"
		)
		(pin "B21"
		)
		(pin "AB23"
		)
		(pin "W13"
		)
		(pin "P2"
		)
		(pin "W16"
		)
		(pin "AC16"
		)
		(pin "H6"
		)
		(pin "Y6"
		)
		(pin "A15"
		)
		(pin "J6"
		)
		(pin "V16"
		)
		(pin "N9"
		)
		(pin "AC21"
		)
		(pin "J19"
		)
		(pin "J20"
		)
		(pin "AC17"
		)
		(pin "AC19"
		)
		(pin "M11"
		)
		(pin "D4"
		)
		(pin "P1"
		)
		(pin "W5"
		)
		(pin "R18"
		)
		(pin "E16"
		)
		(pin "N23"
		)
		(pin "A22"
		)
		(pin "R9"
		)
		(pin "D8"
		)
		(pin "E15"
		)
		(pin "M19"
		)
		(pin "Y20"
		)
		(pin "T9"
		)
		(pin "H13"
		)
		(pin "W15"
		)
		(pin "B10"
		)
		(pin "AC14"
		)
		(pin "AC18"
		)
		(pin "C2"
		)
		(pin "E5"
		)
		(pin "J22"
		)
		(pin "J18"
		)
		(pin "J16"
		)
		(pin "AC8"
		)
		(pin "B1"
		)
		(pin "N2"
		)
		(pin "E11"
		)
		(pin "A18"
		)
		(pin "H1"
		)
		(pin "G23"
		)
		(pin "A16"
		)
		(pin "D11"
		)
		(pin "B15"
		)
		(pin "F8"
		)
		(pin "E12"
		)
		(pin "AA22"
		)
		(pin "D12"
		)
		(pin "F6"
		)
		(instances
			(project "thunderbolt-to-10gbe-adapter"
				(path ""
					(reference "U4")
					(unit 1)
				)
			)
		)
	)
	(symbol
		(lib_id "antmicropower:GND")
		(at 224.79 168.91 0)
		(unit 1)
		(exclude_from_sim no)
		(in_bom yes)
		(on_board yes)
		(dnp no)
		(property "Reference" "#PWR0105"
			(at 224.79 175.26 0)
			(effects
				(font
					(size 1.27 1.27)
				)
				(hide yes)
			)
		)
		(property "Value" "GND"
			(at 224.79 172.72 0)
			(effects
				(font
					(size 1.27 1.27)
				)
			)
		)
		(property "Footprint" ""
			(at 224.79 168.91 0)
			(effects
				(font
					(size 1.27 1.27)
				)
				(hide yes)
			)
		)
		(property "Datasheet" ""
			(at 224.79 168.91 0)
			(effects
				(font
					(size 1.27 1.27)
				)
				(hide yes)
			)
		)
		(property "Description" ""
			(at 224.79 168.91 0)
			(effects
				(font
					(size 1.27 1.27)
				)
				(hide yes)
			)
		)
		(property "Author" "Antmicro"
			(at 233.68 176.53 0)
			(effects
				(font
					(size 1.27 1.27)
					(thickness 0.15)
				)
				(justify left bottom)
				(hide yes)
			)
		)
		(property "License" "Apache-2.0"
			(at 233.68 179.07 0)
			(effects
				(font
					(size 1.27 1.27)
					(thickness 0.15)
				)
				(justify left bottom)
				(hide yes)
			)
		)
		(pin "1"
		)
		(instances
			(project "thunderbolt-to-10gbe-adapter"
				(path ""
					(reference "#PWR0105")
					(unit 1)
				)
			)
		)
	)
	(symbol
		(lib_id "antmicroCapacitors0402:C_100n_0402")
		(at 227.33 78.74 90)
		(unit 1)
		(exclude_from_sim no)
		(in_bom yes)
		(on_board yes)
		(dnp no)
		(property "Reference" "C82"
			(at 227.965 74.295 90)
			(effects
				(font
					(size 1.27 1.27)
					(thickness 0.15)
				)
				(justify right)
			)
		)
		(property "Value" "C_100n_0402"
			(at 237.49 58.42 0)
			(effects
				(font
					(size 1.27 1.27)
					(thickness 0.15)
				)
				(justify left bottom)
				(hide yes)
			)
		)
		(property "Footprint" "antmicro-footprints:C_0402_1005Metric"
			(at 240.03 58.42 0)
			(effects
				(font
					(size 1.27 1.27)
					(thickness 0.15)
				)
				(justify left bottom)
				(hide yes)
			)
		)
		(property "Datasheet" "https://www.murata.com/products/productdetail?partno=GRM155R61H104KE14%23"
			(at 242.57 58.42 0)
			(effects
				(font
					(size 1.27 1.27)
					(thickness 0.15)
				)
				(justify left bottom)
				(hide yes)
			)
		)
		(property "Description" "SMD Multilayer Ceramic Capacitor, 0.1 µF, 50 V, 0402 [1005 Metric], ± 10%, X5R, GRM Series"
			(at 227.33 78.74 0)
			(effects
				(font
					(size 1.27 1.27)
				)
				(hide yes)
			)
		)
		(property "MPN" "GRM155R61H104KE14D"
			(at 245.11 58.42 0)
			(effects
				(font
					(size 1.27 1.27)
					(thickness 0.15)
				)
				(justify left bottom)
				(hide yes)
			)
		)
		(property "Manufacturer" "Murata"
			(at 247.65 58.42 0)
			(effects
				(font
					(size 1.27 1.27)
					(thickness 0.15)
				)
				(justify left bottom)
				(hide yes)
			)
		)
		(property "License" "Apache-2.0"
			(at 250.19 58.42 0)
			(effects
				(font
					(size 1.27 1.27)
					(thickness 0.15)
				)
				(justify left bottom)
				(hide yes)
			)
		)
		(property "Val" "100n"
			(at 227.965 78.105 90)
			(effects
				(font
					(size 1.27 1.27)
					(thickness 0.15)
				)
				(justify right)
			)
		)
		(property "Voltage" "50V"
			(at 255.27 58.42 0)
			(effects
				(font
					(size 1.27 1.27)
				)
				(justify left bottom)
				(hide yes)
			)
		)
		(property "Dielectric" "X5R"
			(at 257.81 58.42 0)
			(effects
				(font
					(size 1.27 1.27)
				)
				(justify left bottom)
				(hide yes)
			)
		)
		(property "Author" "Antmicro"
			(at 252.73 58.42 0)
			(effects
				(font
					(size 1.27 1.27)
					(thickness 0.15)
				)
				(justify left bottom)
				(hide yes)
			)
		)
		(pin "1"
		)
		(pin "2"
		)
		(instances
			(project "thunderbolt-to-10gbe-adapter"
				(path ""
					(reference "C82")
					(unit 1)
				)
			)
		)
	)
	(symbol
		(lib_id "antmicropower:GND")
		(at 227.33 97.79 0)
		(mirror y)
		(unit 1)
		(exclude_from_sim no)
		(in_bom yes)
		(on_board yes)
		(dnp no)
		(property "Reference" "#PWR0108"
			(at 227.33 104.14 0)
			(effects
				(font
					(size 1.27 1.27)
				)
				(hide yes)
			)
		)
		(property "Value" "GND"
			(at 227.33 101.6 0)
			(effects
				(font
					(size 1.27 1.27)
				)
			)
		)
		(property "Footprint" ""
			(at 227.33 97.79 0)
			(effects
				(font
					(size 1.27 1.27)
				)
				(hide yes)
			)
		)
		(property "Datasheet" ""
			(at 227.33 97.79 0)
			(effects
				(font
					(size 1.27 1.27)
				)
				(hide yes)
			)
		)
		(property "Description" ""
			(at 227.33 97.79 0)
			(effects
				(font
					(size 1.27 1.27)
				)
				(hide yes)
			)
		)
		(property "Author" "Antmicro"
			(at 218.44 105.41 0)
			(effects
				(font
					(size 1.27 1.27)
					(thickness 0.15)
				)
				(justify left bottom)
				(hide yes)
			)
		)
		(property "License" "Apache-2.0"
			(at 218.44 107.95 0)
			(effects
				(font
					(size 1.27 1.27)
					(thickness 0.15)
				)
				(justify left bottom)
				(hide yes)
			)
		)
		(pin "1"
		)
		(instances
			(project "thunderbolt-to-10gbe-adapter"
				(path ""
					(reference "#PWR0108")
					(unit 1)
				)
			)
		)
	)
	(symbol
		(lib_id "antmicropower:GND")
		(at 269.24 113.03 0)
		(unit 1)
		(exclude_from_sim no)
		(in_bom yes)
		(on_board yes)
		(dnp no)
		(property "Reference" "#PWR0137"
			(at 269.24 119.38 0)
			(effects
				(font
					(size 1.27 1.27)
				)
				(hide yes)
			)
		)
		(property "Value" "GND"
			(at 269.24 116.84 0)
			(effects
				(font
					(size 1.27 1.27)
				)
			)
		)
		(property "Footprint" ""
			(at 269.24 113.03 0)
			(effects
				(font
					(size 1.27 1.27)
				)
				(hide yes)
			)
		)
		(property "Datasheet" ""
			(at 269.24 113.03 0)
			(effects
				(font
					(size 1.27 1.27)
				)
				(hide yes)
			)
		)
		(property "Description" ""
			(at 269.24 113.03 0)
			(effects
				(font
					(size 1.27 1.27)
				)
				(hide yes)
			)
		)
		(property "Author" "Antmicro"
			(at 278.13 120.65 0)
			(effects
				(font
					(size 1.27 1.27)
					(thickness 0.15)
				)
				(justify left bottom)
				(hide yes)
			)
		)
		(property "License" "Apache-2.0"
			(at 278.13 123.19 0)
			(effects
				(font
					(size 1.27 1.27)
					(thickness 0.15)
				)
				(justify left bottom)
				(hide yes)
			)
		)
		(pin "1"
		)
		(instances
			(project "thunderbolt-to-10gbe-adapter"
				(path ""
					(reference "#PWR0137")
					(unit 1)
				)
			)
		)
	)
	(symbol
		(lib_id "antmicroCapacitors0603:C_22u_0603")
		(at 252.73 147.32 90)
		(unit 1)
		(exclude_from_sim no)
		(in_bom yes)
		(on_board yes)
		(dnp no)
		(property "Reference" "C94"
			(at 253.365 142.875 90)
			(effects
				(font
					(size 1.27 1.27)
					(thickness 0.15)
				)
				(justify right)
			)
		)
		(property "Value" "C_22u_0603"
			(at 262.89 127 0)
			(effects
				(font
					(size 1.27 1.27)
					(thickness 0.15)
				)
				(justify left bottom)
				(hide yes)
			)
		)
		(property "Footprint" "antmicro-footprints:C_0603_1608Metric"
			(at 265.43 127 0)
			(effects
				(font
					(size 1.27 1.27)
					(thickness 0.15)
				)
				(justify left bottom)
				(hide yes)
			)
		)
		(property "Datasheet" "https://www.murata.com/products/productdetail?partno=GRM188R60J226MEA0%23"
			(at 267.97 127 0)
			(effects
				(font
					(size 1.27 1.27)
					(thickness 0.15)
				)
				(justify left bottom)
				(hide yes)
			)
		)
		(property "Description" "SMD Multilayer Ceramic Capacitor, 22 µF, 6.3 V, 0603 [1608 Metric], ± 20%, X5R, GRM Series"
			(at 252.73 147.32 0)
			(effects
				(font
					(size 1.27 1.27)
				)
				(hide yes)
			)
		)
		(property "MPN" "GRM188R60J226MEA0D"
			(at 270.51 127 0)
			(effects
				(font
					(size 1.27 1.27)
					(thickness 0.15)
				)
				(justify left bottom)
				(hide yes)
			)
		)
		(property "Manufacturer" "Murata"
			(at 273.05 127 0)
			(effects
				(font
					(size 1.27 1.27)
					(thickness 0.15)
				)
				(justify left bottom)
				(hide yes)
			)
		)
		(property "License" "Apache-2.0"
			(at 275.59 127 0)
			(effects
				(font
					(size 1.27 1.27)
					(thickness 0.15)
				)
				(justify left bottom)
				(hide yes)
			)
		)
		(property "Val" "22u"
			(at 253.365 146.685 90)
			(effects
				(font
					(size 1.27 1.27)
					(thickness 0.15)
				)
				(justify right)
			)
		)
		(property "Voltage" ""
			(at 280.67 127 0)
			(effects
				(font
					(size 1.27 1.27)
				)
				(justify left bottom)
				(hide yes)
			)
		)
		(property "Dielectric" ""
			(at 283.21 127 0)
			(effects
				(font
					(size 1.27 1.27)
				)
				(justify left bottom)
				(hide yes)
			)
		)
		(property "Author" "Antmicro"
			(at 278.13 127 0)
			(effects
				(font
					(size 1.27 1.27)
					(thickness 0.15)
				)
				(justify left bottom)
				(hide yes)
			)
		)
		(pin "1"
		)
		(pin "2"
		)
		(instances
			(project "thunderbolt-to-10gbe-adapter"
				(path ""
					(reference "C94")
					(unit 1)
				)
			)
		)
	)
	(symbol
		(lib_id "antmicroCapacitors0402:C_1u_0402")
		(at 233.68 95.25 90)
		(unit 1)
		(exclude_from_sim no)
		(in_bom yes)
		(on_board yes)
		(dnp no)
		(property "Reference" "C78"
			(at 234.315 90.805 90)
			(effects
				(font
					(size 1.27 1.27)
					(thickness 0.15)
				)
				(justify right)
			)
		)
		(property "Value" "C_1u_0402"
			(at 243.84 74.93 0)
			(effects
				(font
					(size 1.27 1.27)
					(thickness 0.15)
				)
				(justify left bottom)
				(hide yes)
			)
		)
		(property "Footprint" "antmicro-footprints:C_0402_1005Metric"
			(at 246.38 74.93 0)
			(effects
				(font
					(size 1.27 1.27)
					(thickness 0.15)
				)
				(justify left bottom)
				(hide yes)
			)
		)
		(property "Datasheet" "https://product.tdk.com/en/search/capacitor/ceramic/mlcc/info?part_no=C1005X6S1A105K050BC"
			(at 248.92 74.93 0)
			(effects
				(font
					(size 1.27 1.27)
					(thickness 0.15)
				)
				(justify left bottom)
				(hide yes)
			)
		)
		(property "Description" "SMD Multilayer Ceramic Capacitor, 1 µF, 10 V, 0402 [1005 Metric], ± 10%, X6S, C"
			(at 233.68 95.25 0)
			(effects
				(font
					(size 1.27 1.27)
				)
				(hide yes)
			)
		)
		(property "MPN" "C1005X6S1A105K050BC"
			(at 251.46 74.93 0)
			(effects
				(font
					(size 1.27 1.27)
					(thickness 0.15)
				)
				(justify left bottom)
				(hide yes)
			)
		)
		(property "Manufacturer" "TDK"
			(at 254 74.93 0)
			(effects
				(font
					(size 1.27 1.27)
					(thickness 0.15)
				)
				(justify left bottom)
				(hide yes)
			)
		)
		(property "License" "Apache-2.0"
			(at 256.54 74.93 0)
			(effects
				(font
					(size 1.27 1.27)
					(thickness 0.15)
				)
				(justify left bottom)
				(hide yes)
			)
		)
		(property "Val" "1u"
			(at 234.315 94.615 90)
			(effects
				(font
					(size 1.27 1.27)
					(thickness 0.15)
				)
				(justify right)
			)
		)
		(property "Voltage" ""
			(at 261.62 74.93 0)
			(effects
				(font
					(size 1.27 1.27)
				)
				(justify left bottom)
				(hide yes)
			)
		)
		(property "Dielectric" ""
			(at 264.16 74.93 0)
			(effects
				(font
					(size 1.27 1.27)
				)
				(justify left bottom)
				(hide yes)
			)
		)
		(property "Author" "Antmicro"
			(at 259.08 74.93 0)
			(effects
				(font
					(size 1.27 1.27)
					(thickness 0.15)
				)
				(justify left bottom)
				(hide yes)
			)
		)
		(pin "1"
		)
		(pin "2"
		)
		(instances
			(project "thunderbolt-to-10gbe-adapter"
				(path ""
					(reference "C78")
					(unit 1)
				)
			)
		)
	)
	(symbol
		(lib_id "antmicroCapacitors0402:C_1u_0402")
		(at 142.24 111.76 90)
		(unit 1)
		(exclude_from_sim no)
		(in_bom yes)
		(on_board yes)
		(dnp no)
		(property "Reference" "C55"
			(at 142.875 107.315 90)
			(effects
				(font
					(size 1.27 1.27)
					(thickness 0.15)
				)
				(justify right)
			)
		)
		(property "Value" "C_1u_0402"
			(at 152.4 91.44 0)
			(effects
				(font
					(size 1.27 1.27)
					(thickness 0.15)
				)
				(justify left bottom)
				(hide yes)
			)
		)
		(property "Footprint" "antmicro-footprints:C_0402_1005Metric"
			(at 154.94 91.44 0)
			(effects
				(font
					(size 1.27 1.27)
					(thickness 0.15)
				)
				(justify left bottom)
				(hide yes)
			)
		)
		(property "Datasheet" "https://product.tdk.com/en/search/capacitor/ceramic/mlcc/info?part_no=C1005X6S1A105K050BC"
			(at 157.48 91.44 0)
			(effects
				(font
					(size 1.27 1.27)
					(thickness 0.15)
				)
				(justify left bottom)
				(hide yes)
			)
		)
		(property "Description" "SMD Multilayer Ceramic Capacitor, 1 µF, 10 V, 0402 [1005 Metric], ± 10%, X6S, C"
			(at 142.24 111.76 0)
			(effects
				(font
					(size 1.27 1.27)
				)
				(hide yes)
			)
		)
		(property "MPN" "C1005X6S1A105K050BC"
			(at 160.02 91.44 0)
			(effects
				(font
					(size 1.27 1.27)
					(thickness 0.15)
				)
				(justify left bottom)
				(hide yes)
			)
		)
		(property "Manufacturer" "TDK"
			(at 162.56 91.44 0)
			(effects
				(font
					(size 1.27 1.27)
					(thickness 0.15)
				)
				(justify left bottom)
				(hide yes)
			)
		)
		(property "License" "Apache-2.0"
			(at 165.1 91.44 0)
			(effects
				(font
					(size 1.27 1.27)
					(thickness 0.15)
				)
				(justify left bottom)
				(hide yes)
			)
		)
		(property "Val" "1u"
			(at 142.875 111.125 90)
			(effects
				(font
					(size 1.27 1.27)
					(thickness 0.15)
				)
				(justify right)
			)
		)
		(property "Voltage" ""
			(at 170.18 91.44 0)
			(effects
				(font
					(size 1.27 1.27)
				)
				(justify left bottom)
				(hide yes)
			)
		)
		(property "Dielectric" ""
			(at 172.72 91.44 0)
			(effects
				(font
					(size 1.27 1.27)
				)
				(justify left bottom)
				(hide yes)
			)
		)
		(property "Author" "Antmicro"
			(at 167.64 91.44 0)
			(effects
				(font
					(size 1.27 1.27)
					(thickness 0.15)
				)
				(justify left bottom)
				(hide yes)
			)
		)
		(pin "1"
		)
		(pin "2"
		)
		(instances
			(project "thunderbolt-to-10gbe-adapter"
				(path ""
					(reference "C55")
					(unit 1)
				)
			)
		)
	)
	(symbol
		(lib_id "antmicroCapacitors0402:C_1u_0402")
		(at 233.68 128.27 90)
		(unit 1)
		(exclude_from_sim no)
		(in_bom yes)
		(on_board yes)
		(dnp no)
		(property "Reference" "C79"
			(at 234.95 123.825 90)
			(effects
				(font
					(size 1.27 1.27)
					(thickness 0.15)
				)
				(justify right)
			)
		)
		(property "Value" "C_1u_0402"
			(at 243.84 107.95 0)
			(effects
				(font
					(size 1.27 1.27)
					(thickness 0.15)
				)
				(justify left bottom)
				(hide yes)
			)
		)
		(property "Footprint" "antmicro-footprints:C_0402_1005Metric"
			(at 246.38 107.95 0)
			(effects
				(font
					(size 1.27 1.27)
					(thickness 0.15)
				)
				(justify left bottom)
				(hide yes)
			)
		)
		(property "Datasheet" "https://product.tdk.com/en/search/capacitor/ceramic/mlcc/info?part_no=C1005X6S1A105K050BC"
			(at 248.92 107.95 0)
			(effects
				(font
					(size 1.27 1.27)
					(thickness 0.15)
				)
				(justify left bottom)
				(hide yes)
			)
		)
		(property "Description" "SMD Multilayer Ceramic Capacitor, 1 µF, 10 V, 0402 [1005 Metric], ± 10%, X6S, C"
			(at 233.68 128.27 0)
			(effects
				(font
					(size 1.27 1.27)
				)
				(hide yes)
			)
		)
		(property "MPN" "C1005X6S1A105K050BC"
			(at 251.46 107.95 0)
			(effects
				(font
					(size 1.27 1.27)
					(thickness 0.15)
				)
				(justify left bottom)
				(hide yes)
			)
		)
		(property "Manufacturer" "TDK"
			(at 254 107.95 0)
			(effects
				(font
					(size 1.27 1.27)
					(thickness 0.15)
				)
				(justify left bottom)
				(hide yes)
			)
		)
		(property "License" "Apache-2.0"
			(at 256.54 107.95 0)
			(effects
				(font
					(size 1.27 1.27)
					(thickness 0.15)
				)
				(justify left bottom)
				(hide yes)
			)
		)
		(property "Val" "1u"
			(at 234.315 127.635 90)
			(effects
				(font
					(size 1.27 1.27)
					(thickness 0.15)
				)
				(justify right)
			)
		)
		(property "Voltage" ""
			(at 261.62 107.95 0)
			(effects
				(font
					(size 1.27 1.27)
				)
				(justify left bottom)
				(hide yes)
			)
		)
		(property "Dielectric" ""
			(at 264.16 107.95 0)
			(effects
				(font
					(size 1.27 1.27)
				)
				(justify left bottom)
				(hide yes)
			)
		)
		(property "Author" "Antmicro"
			(at 259.08 107.95 0)
			(effects
				(font
					(size 1.27 1.27)
					(thickness 0.15)
				)
				(justify left bottom)
				(hide yes)
			)
		)
		(pin "1"
		)
		(pin "2"
		)
		(instances
			(project "thunderbolt-to-10gbe-adapter"
				(path ""
					(reference "C79")
					(unit 1)
				)
			)
		)
	)
	(symbol
		(lib_id "antmicropower:PWR_FLAG")
		(at 154.94 83.82 0)
		(unit 1)
		(exclude_from_sim no)
		(in_bom yes)
		(on_board yes)
		(dnp no)
		(property "Reference" "#FLG014"
			(at 154.94 81.915 0)
			(effects
				(font
					(size 1.27 1.27)
				)
				(hide yes)
			)
		)
		(property "Value" "PWR_FLAG"
			(at 154.94 80.01 0)
			(effects
				(font
					(size 1.27 1.27)
				)
			)
		)
		(property "Footprint" ""
			(at 154.94 83.82 0)
			(effects
				(font
					(size 1.27 1.27)
				)
				(hide yes)
			)
		)
		(property "Datasheet" ""
			(at 154.94 83.82 0)
			(effects
				(font
					(size 1.27 1.27)
				)
				(hide yes)
			)
		)
		(property "Description" ""
			(at 154.94 86.36 0)
			(effects
				(font
					(size 1.27 1.27)
				)
				(justify left bottom)
				(hide yes)
			)
		)
		(pin "1"
		)
		(instances
			(project "thunderbolt-to-10gbe-adapter"
				(path ""
					(reference "#FLG014")
					(unit 1)
				)
			)
		)
	)
	(symbol
		(lib_id "antmicropower:+3V3")
		(at 284.48 101.6 0)
		(unit 1)
		(exclude_from_sim no)
		(in_bom yes)
		(on_board yes)
		(dnp no)
		(property "Reference" "#PWR0141"
			(at 299.72 101.6 0)
			(effects
				(font
					(size 1.27 1.27)
					(thickness 0.15)
				)
				(justify left bottom)
				(hide yes)
			)
		)
		(property "Value" "+3V3_TB"
			(at 284.48 97.79 0)
			(effects
				(font
					(size 1.27 1.27)
					(thickness 0.15)
				)
			)
		)
		(property "Footprint" ""
			(at 299.72 109.22 0)
			(effects
				(font
					(size 1.27 1.27)
					(thickness 0.15)
				)
				(justify left bottom)
				(hide yes)
			)
		)
		(property "Datasheet" ""
			(at 299.72 111.76 0)
			(effects
				(font
					(size 1.27 1.27)
					(thickness 0.15)
				)
				(justify left bottom)
				(hide yes)
			)
		)
		(property "Description" ""
			(at 299.72 114.3 0)
			(effects
				(font
					(size 1.27 1.27)
				)
				(justify left bottom)
				(hide yes)
			)
		)
		(property "Author" "Antmicro"
			(at 299.72 104.14 0)
			(effects
				(font
					(size 1.27 1.27)
					(thickness 0.15)
				)
				(justify left bottom)
				(hide yes)
			)
		)
		(property "License" "Apache-2.0"
			(at 299.72 106.68 0)
			(effects
				(font
					(size 1.27 1.27)
					(thickness 0.15)
				)
				(justify left bottom)
				(hide yes)
			)
		)
		(pin "1"
		)
		(instances
			(project "thunderbolt-to-10gbe-adapter"
				(path ""
					(reference "#PWR0141")
					(unit 1)
				)
			)
		)
	)
	(symbol
		(lib_id "antmicroCapacitors0402:C_1u_0402")
		(at 152.4 93.98 90)
		(unit 1)
		(exclude_from_sim no)
		(in_bom yes)
		(on_board yes)
		(dnp no)
		(property "Reference" "C59"
			(at 153.035 89.535 90)
			(effects
				(font
					(size 1.27 1.27)
					(thickness 0.15)
				)
				(justify right)
			)
		)
		(property "Value" "C_1u_0402"
			(at 162.56 73.66 0)
			(effects
				(font
					(size 1.27 1.27)
					(thickness 0.15)
				)
				(justify left bottom)
				(hide yes)
			)
		)
		(property "Footprint" "antmicro-footprints:C_0402_1005Metric"
			(at 165.1 73.66 0)
			(effects
				(font
					(size 1.27 1.27)
					(thickness 0.15)
				)
				(justify left bottom)
				(hide yes)
			)
		)
		(property "Datasheet" "https://product.tdk.com/en/search/capacitor/ceramic/mlcc/info?part_no=C1005X6S1A105K050BC"
			(at 167.64 73.66 0)
			(effects
				(font
					(size 1.27 1.27)
					(thickness 0.15)
				)
				(justify left bottom)
				(hide yes)
			)
		)
		(property "Description" "SMD Multilayer Ceramic Capacitor, 1 µF, 10 V, 0402 [1005 Metric], ± 10%, X6S, C"
			(at 152.4 93.98 0)
			(effects
				(font
					(size 1.27 1.27)
				)
				(hide yes)
			)
		)
		(property "MPN" "C1005X6S1A105K050BC"
			(at 170.18 73.66 0)
			(effects
				(font
					(size 1.27 1.27)
					(thickness 0.15)
				)
				(justify left bottom)
				(hide yes)
			)
		)
		(property "Manufacturer" "TDK"
			(at 172.72 73.66 0)
			(effects
				(font
					(size 1.27 1.27)
					(thickness 0.15)
				)
				(justify left bottom)
				(hide yes)
			)
		)
		(property "License" "Apache-2.0"
			(at 175.26 73.66 0)
			(effects
				(font
					(size 1.27 1.27)
					(thickness 0.15)
				)
				(justify left bottom)
				(hide yes)
			)
		)
		(property "Val" "1u"
			(at 153.035 93.345 90)
			(effects
				(font
					(size 1.27 1.27)
					(thickness 0.15)
				)
				(justify right)
			)
		)
		(property "Voltage" ""
			(at 180.34 73.66 0)
			(effects
				(font
					(size 1.27 1.27)
				)
				(justify left bottom)
				(hide yes)
			)
		)
		(property "Dielectric" ""
			(at 182.88 73.66 0)
			(effects
				(font
					(size 1.27 1.27)
				)
				(justify left bottom)
				(hide yes)
			)
		)
		(property "Author" "Antmicro"
			(at 177.8 73.66 0)
			(effects
				(font
					(size 1.27 1.27)
					(thickness 0.15)
				)
				(justify left bottom)
				(hide yes)
			)
		)
		(pin "1"
		)
		(pin "2"
		)
		(instances
			(project "thunderbolt-to-10gbe-adapter"
				(path ""
					(reference "C59")
					(unit 1)
				)
			)
		)
	)
	(symbol
		(lib_id "antmicroCapacitors0402:C_1u_0402")
		(at 142.24 93.98 90)
		(unit 1)
		(exclude_from_sim no)
		(in_bom yes)
		(on_board yes)
		(dnp no)
		(property "Reference" "C54"
			(at 142.875 89.535 90)
			(effects
				(font
					(size 1.27 1.27)
					(thickness 0.15)
				)
				(justify right)
			)
		)
		(property "Value" "C_1u_0402"
			(at 152.4 73.66 0)
			(effects
				(font
					(size 1.27 1.27)
					(thickness 0.15)
				)
				(justify left bottom)
				(hide yes)
			)
		)
		(property "Footprint" "antmicro-footprints:C_0402_1005Metric"
			(at 154.94 73.66 0)
			(effects
				(font
					(size 1.27 1.27)
					(thickness 0.15)
				)
				(justify left bottom)
				(hide yes)
			)
		)
		(property "Datasheet" "https://product.tdk.com/en/search/capacitor/ceramic/mlcc/info?part_no=C1005X6S1A105K050BC"
			(at 157.48 73.66 0)
			(effects
				(font
					(size 1.27 1.27)
					(thickness 0.15)
				)
				(justify left bottom)
				(hide yes)
			)
		)
		(property "Description" "SMD Multilayer Ceramic Capacitor, 1 µF, 10 V, 0402 [1005 Metric], ± 10%, X6S, C"
			(at 142.24 93.98 0)
			(effects
				(font
					(size 1.27 1.27)
				)
				(hide yes)
			)
		)
		(property "MPN" "C1005X6S1A105K050BC"
			(at 160.02 73.66 0)
			(effects
				(font
					(size 1.27 1.27)
					(thickness 0.15)
				)
				(justify left bottom)
				(hide yes)
			)
		)
		(property "Manufacturer" "TDK"
			(at 162.56 73.66 0)
			(effects
				(font
					(size 1.27 1.27)
					(thickness 0.15)
				)
				(justify left bottom)
				(hide yes)
			)
		)
		(property "License" "Apache-2.0"
			(at 165.1 73.66 0)
			(effects
				(font
					(size 1.27 1.27)
					(thickness 0.15)
				)
				(justify left bottom)
				(hide yes)
			)
		)
		(property "Val" "1u"
			(at 142.875 93.345 90)
			(effects
				(font
					(size 1.27 1.27)
					(thickness 0.15)
				)
				(justify right)
			)
		)
		(property "Voltage" ""
			(at 170.18 73.66 0)
			(effects
				(font
					(size 1.27 1.27)
				)
				(justify left bottom)
				(hide yes)
			)
		)
		(property "Dielectric" ""
			(at 172.72 73.66 0)
			(effects
				(font
					(size 1.27 1.27)
				)
				(justify left bottom)
				(hide yes)
			)
		)
		(property "Author" "Antmicro"
			(at 167.64 73.66 0)
			(effects
				(font
					(size 1.27 1.27)
					(thickness 0.15)
				)
				(justify left bottom)
				(hide yes)
			)
		)
		(pin "1"
		)
		(pin "2"
		)
		(instances
			(project "thunderbolt-to-10gbe-adapter"
				(path ""
					(reference "C54")
					(unit 1)
				)
			)
		)
	)
	(symbol
		(lib_id "antmicropower:GND")
		(at 240.03 168.91 0)
		(unit 1)
		(exclude_from_sim no)
		(in_bom yes)
		(on_board yes)
		(dnp no)
		(property "Reference" "#PWR0118"
			(at 240.03 175.26 0)
			(effects
				(font
					(size 1.27 1.27)
				)
				(hide yes)
			)
		)
		(property "Value" "GND"
			(at 240.03 172.72 0)
			(effects
				(font
					(size 1.27 1.27)
				)
			)
		)
		(property "Footprint" ""
			(at 240.03 168.91 0)
			(effects
				(font
					(size 1.27 1.27)
				)
				(hide yes)
			)
		)
		(property "Datasheet" ""
			(at 240.03 168.91 0)
			(effects
				(font
					(size 1.27 1.27)
				)
				(hide yes)
			)
		)
		(property "Description" ""
			(at 240.03 168.91 0)
			(effects
				(font
					(size 1.27 1.27)
				)
				(hide yes)
			)
		)
		(property "Author" "Antmicro"
			(at 248.92 176.53 0)
			(effects
				(font
					(size 1.27 1.27)
					(thickness 0.15)
				)
				(justify left bottom)
				(hide yes)
			)
		)
		(property "License" "Apache-2.0"
			(at 248.92 179.07 0)
			(effects
				(font
					(size 1.27 1.27)
					(thickness 0.15)
				)
				(justify left bottom)
				(hide yes)
			)
		)
		(pin "1"
		)
		(instances
			(project "thunderbolt-to-10gbe-adapter"
				(path ""
					(reference "#PWR0118")
					(unit 1)
				)
			)
		)
	)
	(symbol
		(lib_id "antmicroCapacitors0402:C_100n_0402")
		(at 233.68 78.74 90)
		(unit 1)
		(exclude_from_sim no)
		(in_bom yes)
		(on_board yes)
		(dnp no)
		(property "Reference" "C86"
			(at 234.315 74.295 90)
			(effects
				(font
					(size 1.27 1.27)
					(thickness 0.15)
				)
				(justify right)
			)
		)
		(property "Value" "C_100n_0402"
			(at 243.84 58.42 0)
			(effects
				(font
					(size 1.27 1.27)
					(thickness 0.15)
				)
				(justify left bottom)
				(hide yes)
			)
		)
		(property "Footprint" "antmicro-footprints:C_0402_1005Metric"
			(at 246.38 58.42 0)
			(effects
				(font
					(size 1.27 1.27)
					(thickness 0.15)
				)
				(justify left bottom)
				(hide yes)
			)
		)
		(property "Datasheet" "https://www.murata.com/products/productdetail?partno=GRM155R61H104KE14%23"
			(at 248.92 58.42 0)
			(effects
				(font
					(size 1.27 1.27)
					(thickness 0.15)
				)
				(justify left bottom)
				(hide yes)
			)
		)
		(property "Description" "SMD Multilayer Ceramic Capacitor, 0.1 µF, 50 V, 0402 [1005 Metric], ± 10%, X5R, GRM Series"
			(at 233.68 78.74 0)
			(effects
				(font
					(size 1.27 1.27)
				)
				(hide yes)
			)
		)
		(property "MPN" "GRM155R61H104KE14D"
			(at 251.46 58.42 0)
			(effects
				(font
					(size 1.27 1.27)
					(thickness 0.15)
				)
				(justify left bottom)
				(hide yes)
			)
		)
		(property "Manufacturer" "Murata"
			(at 254 58.42 0)
			(effects
				(font
					(size 1.27 1.27)
					(thickness 0.15)
				)
				(justify left bottom)
				(hide yes)
			)
		)
		(property "License" "Apache-2.0"
			(at 256.54 58.42 0)
			(effects
				(font
					(size 1.27 1.27)
					(thickness 0.15)
				)
				(justify left bottom)
				(hide yes)
			)
		)
		(property "Val" "100n"
			(at 234.315 78.105 90)
			(effects
				(font
					(size 1.27 1.27)
					(thickness 0.15)
				)
				(justify right)
			)
		)
		(property "Voltage" "50V"
			(at 261.62 58.42 0)
			(effects
				(font
					(size 1.27 1.27)
				)
				(justify left bottom)
				(hide yes)
			)
		)
		(property "Dielectric" "X5R"
			(at 264.16 58.42 0)
			(effects
				(font
					(size 1.27 1.27)
				)
				(justify left bottom)
				(hide yes)
			)
		)
		(property "Author" "Antmicro"
			(at 259.08 58.42 0)
			(effects
				(font
					(size 1.27 1.27)
					(thickness 0.15)
				)
				(justify left bottom)
				(hide yes)
			)
		)
		(pin "1"
		)
		(pin "2"
		)
		(instances
			(project "thunderbolt-to-10gbe-adapter"
				(path ""
					(reference "C86")
					(unit 1)
				)
			)
		)
	)
	(symbol
		(lib_id "antmicroCapacitors0402:C_10u_0402")
		(at 259.08 78.74 90)
		(unit 1)
		(exclude_from_sim no)
		(in_bom yes)
		(on_board yes)
		(dnp no)
		(property "Reference" "C100"
			(at 259.715 74.295 90)
			(effects
				(font
					(size 1.27 1.27)
					(thickness 0.15)
				)
				(justify right)
			)
		)
		(property "Value" "C_10u_0402"
			(at 269.24 58.42 0)
			(effects
				(font
					(size 1.27 1.27)
					(thickness 0.15)
				)
				(justify left bottom)
				(hide yes)
			)
		)
		(property "Footprint" "antmicro-footprints:C_0402_1005Metric"
			(at 271.78 58.42 0)
			(effects
				(font
					(size 1.27 1.27)
					(thickness 0.15)
				)
				(justify left bottom)
				(hide yes)
			)
		)
		(property "Datasheet" "https://www.yageo.com/en/Chart/Download/pdf/CC0402MRX5R5BB106"
			(at 274.32 58.42 0)
			(effects
				(font
					(size 1.27 1.27)
					(thickness 0.15)
				)
				(justify left bottom)
				(hide yes)
			)
		)
		(property "Description" "SMD Multilayer Ceramic Capacitor, 10 µF, 6.3 V, 0402 [1005 Metric], ± 20%, X5R, CC Series"
			(at 259.08 78.74 0)
			(effects
				(font
					(size 1.27 1.27)
				)
				(hide yes)
			)
		)
		(property "MPN" "CC0402MRX5R5BB106"
			(at 276.86 58.42 0)
			(effects
				(font
					(size 1.27 1.27)
					(thickness 0.15)
				)
				(justify left bottom)
				(hide yes)
			)
		)
		(property "Manufacturer" "YAGEO"
			(at 279.4 58.42 0)
			(effects
				(font
					(size 1.27 1.27)
					(thickness 0.15)
				)
				(justify left bottom)
				(hide yes)
			)
		)
		(property "License" "Apache-2.0"
			(at 281.94 58.42 0)
			(effects
				(font
					(size 1.27 1.27)
					(thickness 0.15)
				)
				(justify left bottom)
				(hide yes)
			)
		)
		(property "Val" "10u"
			(at 259.715 78.105 90)
			(effects
				(font
					(size 1.27 1.27)
					(thickness 0.15)
				)
				(justify right)
			)
		)
		(property "Voltage" ""
			(at 287.02 58.42 0)
			(effects
				(font
					(size 1.27 1.27)
				)
				(justify left bottom)
				(hide yes)
			)
		)
		(property "Dielectric" ""
			(at 289.56 58.42 0)
			(effects
				(font
					(size 1.27 1.27)
				)
				(justify left bottom)
				(hide yes)
			)
		)
		(property "Author" "Antmicro"
			(at 284.48 58.42 0)
			(effects
				(font
					(size 1.27 1.27)
					(thickness 0.15)
				)
				(justify left bottom)
				(hide yes)
			)
		)
		(pin "1"
		)
		(pin "2"
		)
		(instances
			(project "thunderbolt-to-10gbe-adapter"
				(path ""
					(reference "C100")
					(unit 1)
				)
			)
		)
	)
	(symbol
		(lib_id "antmicroResistors0402:R_330R_0402")
		(at 254 209.55 90)
		(unit 1)
		(exclude_from_sim no)
		(in_bom yes)
		(on_board yes)
		(dnp no)
		(fields_autoplaced yes)
		(property "Reference" "R74"
			(at 256.54 205.7399 90)
			(effects
				(font
					(size 1.27 1.27)
					(thickness 0.15)
				)
				(justify right)
			)
		)
		(property "Value" "R_330R_0402"
			(at 266.7 189.23 0)
			(effects
				(font
					(size 1.27 1.27)
					(thickness 0.15)
				)
				(justify left bottom)
				(hide yes)
			)
		)
		(property "Footprint" "antmicro-footprints:R_0402_1005Metric"
			(at 269.24 189.23 0)
			(effects
				(font
					(size 1.27 1.27)
					(thickness 0.15)
				)
				(justify left bottom)
				(hide yes)
			)
		)
		(property "Datasheet" "https://www.bourns.com/docs/product-datasheets/cr.pdf"
			(at 271.78 189.23 0)
			(effects
				(font
					(size 1.27 1.27)
					(thickness 0.15)
				)
				(justify left bottom)
				(hide yes)
			)
		)
		(property "Description" "SMD Chip Resistor, 330 ohm, ± 1%, 62.5 mW, 0402 [1005 Metric], Thick Film, General Purpose"
			(at 254 209.55 0)
			(effects
				(font
					(size 1.27 1.27)
				)
				(hide yes)
			)
		)
		(property "MPN" "CR0402-FX-3300GLF"
			(at 274.32 189.23 0)
			(effects
				(font
					(size 1.27 1.27)
					(thickness 0.15)
				)
				(justify left bottom)
				(hide yes)
			)
		)
		(property "Manufacturer" "Bourns"
			(at 276.86 189.23 0)
			(effects
				(font
					(size 1.27 1.27)
					(thickness 0.15)
				)
				(justify left bottom)
				(hide yes)
			)
		)
		(property "License" "Apache-2.0"
			(at 279.4 189.23 0)
			(effects
				(font
					(size 1.27 1.27)
					(thickness 0.15)
				)
				(justify left bottom)
				(hide yes)
			)
		)
		(property "Val" "330R"
			(at 256.54 208.2799 90)
			(effects
				(font
					(size 1.27 1.27)
					(thickness 0.15)
				)
				(justify right)
			)
		)
		(property "Tolerance" "1%"
			(at 264.16 189.23 0)
			(effects
				(font
					(size 1.27 1.27)
				)
				(justify left bottom)
				(hide yes)
			)
		)
		(property "Author" "Antmicro"
			(at 281.94 189.23 0)
			(effects
				(font
					(size 1.27 1.27)
					(thickness 0.15)
				)
				(justify left bottom)
				(hide yes)
			)
		)
		(pin "1"
		)
		(pin "2"
		)
		(instances
			(project "thunderbolt-to-10gbe-adapter"
				(path ""
					(reference "R74")
					(unit 1)
				)
			)
		)
	)
	(symbol
		(lib_id "antmicroCapacitors0402:C_1u_0402")
		(at 153.67 167.64 90)
		(unit 1)
		(exclude_from_sim no)
		(in_bom yes)
		(on_board yes)
		(dnp no)
		(property "Reference" "C62"
			(at 151.765 163.195 90)
			(effects
				(font
					(size 1.27 1.27)
					(thickness 0.15)
				)
				(justify left)
			)
		)
		(property "Value" "C_1u_0402"
			(at 163.83 147.32 0)
			(effects
				(font
					(size 1.27 1.27)
					(thickness 0.15)
				)
				(justify left bottom)
				(hide yes)
			)
		)
		(property "Footprint" "antmicro-footprints:C_0402_1005Metric"
			(at 166.37 147.32 0)
			(effects
				(font
					(size 1.27 1.27)
					(thickness 0.15)
				)
				(justify left bottom)
				(hide yes)
			)
		)
		(property "Datasheet" "https://product.tdk.com/en/search/capacitor/ceramic/mlcc/info?part_no=C1005X6S1A105K050BC"
			(at 168.91 147.32 0)
			(effects
				(font
					(size 1.27 1.27)
					(thickness 0.15)
				)
				(justify left bottom)
				(hide yes)
			)
		)
		(property "Description" "SMD Multilayer Ceramic Capacitor, 1 µF, 10 V, 0402 [1005 Metric], ± 10%, X6S, C"
			(at 153.67 167.64 0)
			(effects
				(font
					(size 1.27 1.27)
				)
				(hide yes)
			)
		)
		(property "MPN" "C1005X6S1A105K050BC"
			(at 171.45 147.32 0)
			(effects
				(font
					(size 1.27 1.27)
					(thickness 0.15)
				)
				(justify left bottom)
				(hide yes)
			)
		)
		(property "Manufacturer" "TDK"
			(at 173.99 147.32 0)
			(effects
				(font
					(size 1.27 1.27)
					(thickness 0.15)
				)
				(justify left bottom)
				(hide yes)
			)
		)
		(property "License" "Apache-2.0"
			(at 176.53 147.32 0)
			(effects
				(font
					(size 1.27 1.27)
					(thickness 0.15)
				)
				(justify left bottom)
				(hide yes)
			)
		)
		(property "Val" "1u"
			(at 151.765 167.005 90)
			(effects
				(font
					(size 1.27 1.27)
					(thickness 0.15)
				)
				(justify left)
			)
		)
		(property "Voltage" ""
			(at 181.61 147.32 0)
			(effects
				(font
					(size 1.27 1.27)
				)
				(justify left bottom)
				(hide yes)
			)
		)
		(property "Dielectric" ""
			(at 184.15 147.32 0)
			(effects
				(font
					(size 1.27 1.27)
				)
				(justify left bottom)
				(hide yes)
			)
		)
		(property "Author" "Antmicro"
			(at 179.07 147.32 0)
			(effects
				(font
					(size 1.27 1.27)
					(thickness 0.15)
				)
				(justify left bottom)
				(hide yes)
			)
		)
		(pin "1"
		)
		(pin "2"
		)
		(instances
			(project "thunderbolt-to-10gbe-adapter"
				(path ""
					(reference "C62")
					(unit 1)
				)
			)
		)
	)
	(symbol
		(lib_id "antmicropower:GND")
		(at 147.32 148.59 0)
		(unit 1)
		(exclude_from_sim no)
		(in_bom yes)
		(on_board yes)
		(dnp no)
		(property "Reference" "#PWR087"
			(at 147.32 154.94 0)
			(effects
				(font
					(size 1.27 1.27)
				)
				(hide yes)
			)
		)
		(property "Value" "GND"
			(at 147.32 152.4 0)
			(effects
				(font
					(size 1.27 1.27)
				)
			)
		)
		(property "Footprint" ""
			(at 147.32 148.59 0)
			(effects
				(font
					(size 1.27 1.27)
				)
				(hide yes)
			)
		)
		(property "Datasheet" ""
			(at 147.32 148.59 0)
			(effects
				(font
					(size 1.27 1.27)
				)
				(hide yes)
			)
		)
		(property "Description" ""
			(at 147.32 148.59 0)
			(effects
				(font
					(size 1.27 1.27)
				)
				(hide yes)
			)
		)
		(property "Author" "Antmicro"
			(at 156.21 156.21 0)
			(effects
				(font
					(size 1.27 1.27)
					(thickness 0.15)
				)
				(justify left bottom)
				(hide yes)
			)
		)
		(property "License" "Apache-2.0"
			(at 156.21 158.75 0)
			(effects
				(font
					(size 1.27 1.27)
					(thickness 0.15)
				)
				(justify left bottom)
				(hide yes)
			)
		)
		(pin "1"
		)
		(instances
			(project "thunderbolt-to-10gbe-adapter"
				(path ""
					(reference "#PWR087")
					(unit 1)
				)
			)
		)
	)
	(symbol
		(lib_id "antmicropower:GND")
		(at 233.68 148.59 0)
		(unit 1)
		(exclude_from_sim no)
		(in_bom yes)
		(on_board yes)
		(dnp no)
		(property "Reference" "#PWR0113"
			(at 233.68 154.94 0)
			(effects
				(font
					(size 1.27 1.27)
				)
				(hide yes)
			)
		)
		(property "Value" "GND"
			(at 233.68 152.4 0)
			(effects
				(font
					(size 1.27 1.27)
				)
			)
		)
		(property "Footprint" ""
			(at 233.68 148.59 0)
			(effects
				(font
					(size 1.27 1.27)
				)
				(hide yes)
			)
		)
		(property "Datasheet" ""
			(at 233.68 148.59 0)
			(effects
				(font
					(size 1.27 1.27)
				)
				(hide yes)
			)
		)
		(property "Description" ""
			(at 233.68 148.59 0)
			(effects
				(font
					(size 1.27 1.27)
				)
				(hide yes)
			)
		)
		(property "Author" "Antmicro"
			(at 242.57 156.21 0)
			(effects
				(font
					(size 1.27 1.27)
					(thickness 0.15)
				)
				(justify left bottom)
				(hide yes)
			)
		)
		(property "License" "Apache-2.0"
			(at 242.57 158.75 0)
			(effects
				(font
					(size 1.27 1.27)
					(thickness 0.15)
				)
				(justify left bottom)
				(hide yes)
			)
		)
		(pin "1"
		)
		(instances
			(project "thunderbolt-to-10gbe-adapter"
				(path ""
					(reference "#PWR0113")
					(unit 1)
				)
			)
		)
	)
	(symbol
		(lib_id "antmicropower:GND")
		(at 246.38 113.03 0)
		(unit 1)
		(exclude_from_sim no)
		(in_bom yes)
		(on_board yes)
		(dnp no)
		(property "Reference" "#PWR0121"
			(at 246.38 119.38 0)
			(effects
				(font
					(size 1.27 1.27)
				)
				(hide yes)
			)
		)
		(property "Value" "GND"
			(at 246.38 116.84 0)
			(effects
				(font
					(size 1.27 1.27)
				)
			)
		)
		(property "Footprint" ""
			(at 246.38 113.03 0)
			(effects
				(font
					(size 1.27 1.27)
				)
				(hide yes)
			)
		)
		(property "Datasheet" ""
			(at 246.38 113.03 0)
			(effects
				(font
					(size 1.27 1.27)
				)
				(hide yes)
			)
		)
		(property "Description" ""
			(at 246.38 113.03 0)
			(effects
				(font
					(size 1.27 1.27)
				)
				(hide yes)
			)
		)
		(property "Author" "Antmicro"
			(at 255.27 120.65 0)
			(effects
				(font
					(size 1.27 1.27)
					(thickness 0.15)
				)
				(justify left bottom)
				(hide yes)
			)
		)
		(property "License" "Apache-2.0"
			(at 255.27 123.19 0)
			(effects
				(font
					(size 1.27 1.27)
					(thickness 0.15)
				)
				(justify left bottom)
				(hide yes)
			)
		)
		(pin "1"
		)
		(instances
			(project "thunderbolt-to-10gbe-adapter"
				(path ""
					(reference "#PWR0121")
					(unit 1)
				)
			)
		)
	)
	(symbol
		(lib_id "antmicropower:GND")
		(at 157.48 132.08 0)
		(unit 1)
		(exclude_from_sim no)
		(in_bom yes)
		(on_board yes)
		(dnp no)
		(property "Reference" "#PWR096"
			(at 157.48 138.43 0)
			(effects
				(font
					(size 1.27 1.27)
				)
				(hide yes)
			)
		)
		(property "Value" "GND"
			(at 157.48 135.89 0)
			(effects
				(font
					(size 1.27 1.27)
				)
			)
		)
		(property "Footprint" ""
			(at 157.48 132.08 0)
			(effects
				(font
					(size 1.27 1.27)
				)
				(hide yes)
			)
		)
		(property "Datasheet" ""
			(at 157.48 132.08 0)
			(effects
				(font
					(size 1.27 1.27)
				)
				(hide yes)
			)
		)
		(property "Description" ""
			(at 157.48 132.08 0)
			(effects
				(font
					(size 1.27 1.27)
				)
				(hide yes)
			)
		)
		(property "Author" "Antmicro"
			(at 166.37 139.7 0)
			(effects
				(font
					(size 1.27 1.27)
					(thickness 0.15)
				)
				(justify left bottom)
				(hide yes)
			)
		)
		(property "License" "Apache-2.0"
			(at 166.37 142.24 0)
			(effects
				(font
					(size 1.27 1.27)
					(thickness 0.15)
				)
				(justify left bottom)
				(hide yes)
			)
		)
		(pin "1"
		)
		(instances
			(project "thunderbolt-to-10gbe-adapter"
				(path ""
					(reference "#PWR096")
					(unit 1)
				)
			)
		)
	)
	(symbol
		(lib_id "antmicropower:PWR_FLAG")
		(at 228.6 105.41 270)
		(unit 1)
		(exclude_from_sim no)
		(in_bom yes)
		(on_board yes)
		(dnp no)
		(fields_autoplaced yes)
		(property "Reference" "#FLG016"
			(at 230.505 105.41 0)
			(effects
				(font
					(size 1.27 1.27)
				)
				(hide yes)
			)
		)
		(property "Value" "PWR_FLAG"
			(at 232.41 105.4099 90)
			(effects
				(font
					(size 1.27 1.27)
				)
				(justify left)
			)
		)
		(property "Footprint" ""
			(at 228.6 105.41 0)
			(effects
				(font
					(size 1.27 1.27)
				)
				(hide yes)
			)
		)
		(property "Datasheet" ""
			(at 228.6 105.41 0)
			(effects
				(font
					(size 1.27 1.27)
				)
				(hide yes)
			)
		)
		(property "Description" ""
			(at 226.06 105.41 0)
			(effects
				(font
					(size 1.27 1.27)
				)
				(justify left bottom)
				(hide yes)
			)
		)
		(pin "1"
		)
		(instances
			(project "thunderbolt-to-10gbe-adapter"
				(path ""
					(reference "#FLG016")
					(unit 1)
				)
			)
		)
	)
	(symbol
		(lib_id "antmicroCapacitors0402:C_1u_0402")
		(at 162.56 111.76 90)
		(unit 1)
		(exclude_from_sim no)
		(in_bom yes)
		(on_board yes)
		(dnp no)
		(property "Reference" "C70"
			(at 163.195 107.315 90)
			(effects
				(font
					(size 1.27 1.27)
					(thickness 0.15)
				)
				(justify right)
			)
		)
		(property "Value" "C_1u_0402"
			(at 172.72 91.44 0)
			(effects
				(font
					(size 1.27 1.27)
					(thickness 0.15)
				)
				(justify left bottom)
				(hide yes)
			)
		)
		(property "Footprint" "antmicro-footprints:C_0402_1005Metric"
			(at 175.26 91.44 0)
			(effects
				(font
					(size 1.27 1.27)
					(thickness 0.15)
				)
				(justify left bottom)
				(hide yes)
			)
		)
		(property "Datasheet" "https://product.tdk.com/en/search/capacitor/ceramic/mlcc/info?part_no=C1005X6S1A105K050BC"
			(at 177.8 91.44 0)
			(effects
				(font
					(size 1.27 1.27)
					(thickness 0.15)
				)
				(justify left bottom)
				(hide yes)
			)
		)
		(property "Description" "SMD Multilayer Ceramic Capacitor, 1 µF, 10 V, 0402 [1005 Metric], ± 10%, X6S, C"
			(at 162.56 111.76 0)
			(effects
				(font
					(size 1.27 1.27)
				)
				(hide yes)
			)
		)
		(property "MPN" "C1005X6S1A105K050BC"
			(at 180.34 91.44 0)
			(effects
				(font
					(size 1.27 1.27)
					(thickness 0.15)
				)
				(justify left bottom)
				(hide yes)
			)
		)
		(property "Manufacturer" "TDK"
			(at 182.88 91.44 0)
			(effects
				(font
					(size 1.27 1.27)
					(thickness 0.15)
				)
				(justify left bottom)
				(hide yes)
			)
		)
		(property "License" "Apache-2.0"
			(at 185.42 91.44 0)
			(effects
				(font
					(size 1.27 1.27)
					(thickness 0.15)
				)
				(justify left bottom)
				(hide yes)
			)
		)
		(property "Val" "1u"
			(at 163.195 111.125 90)
			(effects
				(font
					(size 1.27 1.27)
					(thickness 0.15)
				)
				(justify right)
			)
		)
		(property "Voltage" ""
			(at 190.5 91.44 0)
			(effects
				(font
					(size 1.27 1.27)
				)
				(justify left bottom)
				(hide yes)
			)
		)
		(property "Dielectric" ""
			(at 193.04 91.44 0)
			(effects
				(font
					(size 1.27 1.27)
				)
				(justify left bottom)
				(hide yes)
			)
		)
		(property "Author" "Antmicro"
			(at 187.96 91.44 0)
			(effects
				(font
					(size 1.27 1.27)
					(thickness 0.15)
				)
				(justify left bottom)
				(hide yes)
			)
		)
		(pin "1"
		)
		(pin "2"
		)
		(instances
			(project "thunderbolt-to-10gbe-adapter"
				(path ""
					(reference "C70")
					(unit 1)
				)
			)
		)
	)
	(symbol
		(lib_id "antmicroTransistorsBipolarSingle:BC817-25W")
		(at 247.65 217.17 0)
		(unit 1)
		(exclude_from_sim no)
		(in_bom yes)
		(on_board yes)
		(dnp no)
		(fields_autoplaced yes)
		(property "Reference" "Q1"
			(at 256.54 215.9 0)
			(effects
				(font
					(size 1.27 1.27)
					(thickness 0.15)
				)
				(justify left)
			)
		)
		(property "Value" "BC817-25W"
			(at 270.51 219.71 0)
			(effects
				(font
					(size 1.27 1.27)
					(thickness 0.15)
				)
				(justify left bottom)
				(hide yes)
			)
		)
		(property "Footprint" "antmicro-footprints:SOT-323"
			(at 270.51 222.25 0)
			(effects
				(font
					(size 1.27 1.27)
					(thickness 0.15)
				)
				(justify left bottom)
				(hide yes)
			)
		)
		(property "Datasheet" "https://assets.nexperia.com/documents/data-sheet/BC817W_SER.pdf"
			(at 270.51 224.79 0)
			(effects
				(font
					(size 1.27 1.27)
					(thickness 0.15)
				)
				(justify left bottom)
				(hide yes)
			)
		)
		(property "Description" "Bipolar (BJT) Single Transistor, NPN, 45 V, 500 mA, 200 mW, SOT-323, Surface Mount"
			(at 247.65 217.17 0)
			(effects
				(font
					(size 1.27 1.27)
				)
				(hide yes)
			)
		)
		(property "MPN" "BC817-25W,115"
			(at 256.54 218.44 0)
			(effects
				(font
					(size 1.27 1.27)
					(thickness 0.15)
				)
				(justify left)
			)
		)
		(property "Manufacturer" "Nexperia"
			(at 270.51 229.87 0)
			(effects
				(font
					(size 1.27 1.27)
					(thickness 0.15)
				)
				(justify left bottom)
				(hide yes)
			)
		)
		(property "License" "Apache-2.0"
			(at 270.51 234.95 0)
			(effects
				(font
					(size 1.27 1.27)
					(thickness 0.15)
				)
				(justify left bottom)
				(hide yes)
			)
		)
		(property "Author" "Antmicro"
			(at 270.51 232.41 0)
			(effects
				(font
					(size 1.27 1.27)
					(thickness 0.15)
				)
				(justify left bottom)
				(hide yes)
			)
		)
		(pin "1"
		)
		(pin "2"
		)
		(pin "3"
		)
		(instances
			(project "thunderbolt-to-10gbe-adapter"
				(path ""
					(reference "Q1")
					(unit 1)
				)
			)
		)
	)
	(symbol
		(lib_id "antmicroCapacitors0402:C_1u_0402")
		(at 152.4 147.32 90)
		(unit 1)
		(exclude_from_sim no)
		(in_bom yes)
		(on_board yes)
		(dnp no)
		(property "Reference" "C61"
			(at 153.035 142.875 90)
			(effects
				(font
					(size 1.27 1.27)
					(thickness 0.15)
				)
				(justify right)
			)
		)
		(property "Value" "C_1u_0402"
			(at 162.56 127 0)
			(effects
				(font
					(size 1.27 1.27)
					(thickness 0.15)
				)
				(justify left bottom)
				(hide yes)
			)
		)
		(property "Footprint" "antmicro-footprints:C_0402_1005Metric"
			(at 165.1 127 0)
			(effects
				(font
					(size 1.27 1.27)
					(thickness 0.15)
				)
				(justify left bottom)
				(hide yes)
			)
		)
		(property "Datasheet" "https://product.tdk.com/en/search/capacitor/ceramic/mlcc/info?part_no=C1005X6S1A105K050BC"
			(at 167.64 127 0)
			(effects
				(font
					(size 1.27 1.27)
					(thickness 0.15)
				)
				(justify left bottom)
				(hide yes)
			)
		)
		(property "Description" "SMD Multilayer Ceramic Capacitor, 1 µF, 10 V, 0402 [1005 Metric], ± 10%, X6S, C"
			(at 152.4 147.32 0)
			(effects
				(font
					(size 1.27 1.27)
				)
				(hide yes)
			)
		)
		(property "MPN" "C1005X6S1A105K050BC"
			(at 170.18 127 0)
			(effects
				(font
					(size 1.27 1.27)
					(thickness 0.15)
				)
				(justify left bottom)
				(hide yes)
			)
		)
		(property "Manufacturer" "TDK"
			(at 172.72 127 0)
			(effects
				(font
					(size 1.27 1.27)
					(thickness 0.15)
				)
				(justify left bottom)
				(hide yes)
			)
		)
		(property "License" "Apache-2.0"
			(at 175.26 127 0)
			(effects
				(font
					(size 1.27 1.27)
					(thickness 0.15)
				)
				(justify left bottom)
				(hide yes)
			)
		)
		(property "Val" "1u"
			(at 153.035 146.685 90)
			(effects
				(font
					(size 1.27 1.27)
					(thickness 0.15)
				)
				(justify right)
			)
		)
		(property "Voltage" ""
			(at 180.34 127 0)
			(effects
				(font
					(size 1.27 1.27)
				)
				(justify left bottom)
				(hide yes)
			)
		)
		(property "Dielectric" ""
			(at 182.88 127 0)
			(effects
				(font
					(size 1.27 1.27)
				)
				(justify left bottom)
				(hide yes)
			)
		)
		(property "Author" "Antmicro"
			(at 177.8 127 0)
			(effects
				(font
					(size 1.27 1.27)
					(thickness 0.15)
				)
				(justify left bottom)
				(hide yes)
			)
		)
		(pin "1"
		)
		(pin "2"
		)
		(instances
			(project "thunderbolt-to-10gbe-adapter"
				(path ""
					(reference "C61")
					(unit 1)
				)
			)
		)
	)
	(symbol
		(lib_id "antmicropower:+3V3")
		(at 262.89 153.67 0)
		(unit 1)
		(exclude_from_sim no)
		(in_bom yes)
		(on_board yes)
		(dnp no)
		(property "Reference" "#PWR0134"
			(at 278.13 153.67 0)
			(effects
				(font
					(size 1.27 1.27)
					(thickness 0.15)
				)
				(justify left bottom)
				(hide yes)
			)
		)
		(property "Value" "+3V3_TB"
			(at 262.89 149.86 0)
			(effects
				(font
					(size 1.27 1.27)
					(thickness 0.15)
				)
			)
		)
		(property "Footprint" ""
			(at 278.13 161.29 0)
			(effects
				(font
					(size 1.27 1.27)
					(thickness 0.15)
				)
				(justify left bottom)
				(hide yes)
			)
		)
		(property "Datasheet" ""
			(at 278.13 163.83 0)
			(effects
				(font
					(size 1.27 1.27)
					(thickness 0.15)
				)
				(justify left bottom)
				(hide yes)
			)
		)
		(property "Description" ""
			(at 278.13 166.37 0)
			(effects
				(font
					(size 1.27 1.27)
				)
				(justify left bottom)
				(hide yes)
			)
		)
		(property "Author" "Antmicro"
			(at 278.13 156.21 0)
			(effects
				(font
					(size 1.27 1.27)
					(thickness 0.15)
				)
				(justify left bottom)
				(hide yes)
			)
		)
		(property "License" "Apache-2.0"
			(at 278.13 158.75 0)
			(effects
				(font
					(size 1.27 1.27)
					(thickness 0.15)
				)
				(justify left bottom)
				(hide yes)
			)
		)
		(pin "1"
		)
		(instances
			(project "thunderbolt-to-10gbe-adapter"
				(path ""
					(reference "#PWR0134")
					(unit 1)
				)
			)
		)
	)
	(symbol
		(lib_id "antmicropower:GND")
		(at 259.08 80.01 0)
		(unit 1)
		(exclude_from_sim no)
		(in_bom yes)
		(on_board yes)
		(dnp no)
		(property "Reference" "#PWR0138"
			(at 259.08 86.36 0)
			(effects
				(font
					(size 1.27 1.27)
				)
				(hide yes)
			)
		)
		(property "Value" "GND"
			(at 259.08 83.82 0)
			(effects
				(font
					(size 1.27 1.27)
				)
			)
		)
		(property "Footprint" ""
			(at 259.08 80.01 0)
			(effects
				(font
					(size 1.27 1.27)
				)
				(hide yes)
			)
		)
		(property "Datasheet" ""
			(at 259.08 80.01 0)
			(effects
				(font
					(size 1.27 1.27)
				)
				(hide yes)
			)
		)
		(property "Description" ""
			(at 259.08 80.01 0)
			(effects
				(font
					(size 1.27 1.27)
				)
				(hide yes)
			)
		)
		(property "Author" "Antmicro"
			(at 267.97 87.63 0)
			(effects
				(font
					(size 1.27 1.27)
					(thickness 0.15)
				)
				(justify left bottom)
				(hide yes)
			)
		)
		(property "License" "Apache-2.0"
			(at 267.97 90.17 0)
			(effects
				(font
					(size 1.27 1.27)
					(thickness 0.15)
				)
				(justify left bottom)
				(hide yes)
			)
		)
		(pin "1"
		)
		(instances
			(project "thunderbolt-to-10gbe-adapter"
				(path ""
					(reference "#PWR0138")
					(unit 1)
				)
			)
		)
	)
	(symbol
		(lib_id "antmicroCapacitors0402:C_10u_0402")
		(at 265.43 78.74 90)
		(unit 1)
		(exclude_from_sim no)
		(in_bom yes)
		(on_board yes)
		(dnp no)
		(property "Reference" "C101"
			(at 266.065 74.295 90)
			(effects
				(font
					(size 1.27 1.27)
					(thickness 0.15)
				)
				(justify right)
			)
		)
		(property "Value" "C_10u_0402"
			(at 275.59 58.42 0)
			(effects
				(font
					(size 1.27 1.27)
					(thickness 0.15)
				)
				(justify left bottom)
				(hide yes)
			)
		)
		(property "Footprint" "antmicro-footprints:C_0402_1005Metric"
			(at 278.13 58.42 0)
			(effects
				(font
					(size 1.27 1.27)
					(thickness 0.15)
				)
				(justify left bottom)
				(hide yes)
			)
		)
		(property "Datasheet" "https://www.yageo.com/en/Chart/Download/pdf/CC0402MRX5R5BB106"
			(at 280.67 58.42 0)
			(effects
				(font
					(size 1.27 1.27)
					(thickness 0.15)
				)
				(justify left bottom)
				(hide yes)
			)
		)
		(property "Description" "SMD Multilayer Ceramic Capacitor, 10 µF, 6.3 V, 0402 [1005 Metric], ± 20%, X5R, CC Series"
			(at 265.43 78.74 0)
			(effects
				(font
					(size 1.27 1.27)
				)
				(hide yes)
			)
		)
		(property "MPN" "CC0402MRX5R5BB106"
			(at 283.21 58.42 0)
			(effects
				(font
					(size 1.27 1.27)
					(thickness 0.15)
				)
				(justify left bottom)
				(hide yes)
			)
		)
		(property "Manufacturer" "YAGEO"
			(at 285.75 58.42 0)
			(effects
				(font
					(size 1.27 1.27)
					(thickness 0.15)
				)
				(justify left bottom)
				(hide yes)
			)
		)
		(property "License" "Apache-2.0"
			(at 288.29 58.42 0)
			(effects
				(font
					(size 1.27 1.27)
					(thickness 0.15)
				)
				(justify left bottom)
				(hide yes)
			)
		)
		(property "Val" "10u"
			(at 266.065 78.105 90)
			(effects
				(font
					(size 1.27 1.27)
					(thickness 0.15)
				)
				(justify right)
			)
		)
		(property "Voltage" ""
			(at 293.37 58.42 0)
			(effects
				(font
					(size 1.27 1.27)
				)
				(justify left bottom)
				(hide yes)
			)
		)
		(property "Dielectric" ""
			(at 295.91 58.42 0)
			(effects
				(font
					(size 1.27 1.27)
				)
				(justify left bottom)
				(hide yes)
			)
		)
		(property "Author" "Antmicro"
			(at 290.83 58.42 0)
			(effects
				(font
					(size 1.27 1.27)
					(thickness 0.15)
				)
				(justify left bottom)
				(hide yes)
			)
		)
		(pin "1"
		)
		(pin "2"
		)
		(instances
			(project "thunderbolt-to-10gbe-adapter"
				(path ""
					(reference "C101")
					(unit 1)
				)
			)
		)
	)
	(symbol
		(lib_id "antmicropower:GND")
		(at 138.43 224.79 0)
		(unit 1)
		(exclude_from_sim no)
		(in_bom yes)
		(on_board yes)
		(dnp no)
		(property "Reference" "#PWR082"
			(at 138.43 231.14 0)
			(effects
				(font
					(size 1.27 1.27)
				)
				(hide yes)
			)
		)
		(property "Value" "GND"
			(at 138.43 228.6 0)
			(effects
				(font
					(size 1.27 1.27)
				)
			)
		)
		(property "Footprint" ""
			(at 138.43 224.79 0)
			(effects
				(font
					(size 1.27 1.27)
				)
				(hide yes)
			)
		)
		(property "Datasheet" ""
			(at 138.43 224.79 0)
			(effects
				(font
					(size 1.27 1.27)
				)
				(hide yes)
			)
		)
		(property "Description" ""
			(at 138.43 224.79 0)
			(effects
				(font
					(size 1.27 1.27)
				)
				(hide yes)
			)
		)
		(property "Author" "Antmicro"
			(at 147.32 232.41 0)
			(effects
				(font
					(size 1.27 1.27)
					(thickness 0.15)
				)
				(justify left bottom)
				(hide yes)
			)
		)
		(property "License" "Apache-2.0"
			(at 147.32 234.95 0)
			(effects
				(font
					(size 1.27 1.27)
					(thickness 0.15)
				)
				(justify left bottom)
				(hide yes)
			)
		)
		(pin "1"
		)
		(instances
			(project "thunderbolt-to-10gbe-adapter"
				(path ""
					(reference "#PWR082")
					(unit 1)
				)
			)
		)
	)
	(symbol
		(lib_id "antmicropower:GND")
		(at 246.38 129.54 0)
		(unit 1)
		(exclude_from_sim no)
		(in_bom yes)
		(on_board yes)
		(dnp no)
		(property "Reference" "#PWR0122"
			(at 246.38 135.89 0)
			(effects
				(font
					(size 1.27 1.27)
				)
				(hide yes)
			)
		)
		(property "Value" "GND"
			(at 246.38 133.35 0)
			(effects
				(font
					(size 1.27 1.27)
				)
			)
		)
		(property "Footprint" ""
			(at 246.38 129.54 0)
			(effects
				(font
					(size 1.27 1.27)
				)
				(hide yes)
			)
		)
		(property "Datasheet" ""
			(at 246.38 129.54 0)
			(effects
				(font
					(size 1.27 1.27)
				)
				(hide yes)
			)
		)
		(property "Description" ""
			(at 246.38 129.54 0)
			(effects
				(font
					(size 1.27 1.27)
				)
				(hide yes)
			)
		)
		(property "Author" "Antmicro"
			(at 255.27 137.16 0)
			(effects
				(font
					(size 1.27 1.27)
					(thickness 0.15)
				)
				(justify left bottom)
				(hide yes)
			)
		)
		(property "License" "Apache-2.0"
			(at 255.27 139.7 0)
			(effects
				(font
					(size 1.27 1.27)
					(thickness 0.15)
				)
				(justify left bottom)
				(hide yes)
			)
		)
		(pin "1"
		)
		(instances
			(project "thunderbolt-to-10gbe-adapter"
				(path ""
					(reference "#PWR0122")
					(unit 1)
				)
			)
		)
	)
	(symbol
		(lib_id "antmicropower:GND")
		(at 227.33 80.01 0)
		(unit 1)
		(exclude_from_sim no)
		(in_bom yes)
		(on_board yes)
		(dnp no)
		(property "Reference" "#PWR0115"
			(at 227.33 86.36 0)
			(effects
				(font
					(size 1.27 1.27)
				)
				(hide yes)
			)
		)
		(property "Value" "GND"
			(at 227.33 83.82 0)
			(effects
				(font
					(size 1.27 1.27)
				)
			)
		)
		(property "Footprint" ""
			(at 227.33 80.01 0)
			(effects
				(font
					(size 1.27 1.27)
				)
				(hide yes)
			)
		)
		(property "Datasheet" ""
			(at 227.33 80.01 0)
			(effects
				(font
					(size 1.27 1.27)
				)
				(hide yes)
			)
		)
		(property "Description" ""
			(at 227.33 80.01 0)
			(effects
				(font
					(size 1.27 1.27)
				)
				(hide yes)
			)
		)
		(property "Author" "Antmicro"
			(at 236.22 87.63 0)
			(effects
				(font
					(size 1.27 1.27)
					(thickness 0.15)
				)
				(justify left bottom)
				(hide yes)
			)
		)
		(property "License" "Apache-2.0"
			(at 236.22 90.17 0)
			(effects
				(font
					(size 1.27 1.27)
					(thickness 0.15)
				)
				(justify left bottom)
				(hide yes)
			)
		)
		(pin "1"
		)
		(instances
			(project "thunderbolt-to-10gbe-adapter"
				(path ""
					(reference "#PWR0115")
					(unit 1)
				)
			)
		)
	)
	(symbol
		(lib_id "antmicropower:GND")
		(at 157.48 148.59 0)
		(unit 1)
		(exclude_from_sim no)
		(in_bom yes)
		(on_board yes)
		(dnp no)
		(property "Reference" "#PWR097"
			(at 157.48 154.94 0)
			(effects
				(font
					(size 1.27 1.27)
				)
				(hide yes)
			)
		)
		(property "Value" "GND"
			(at 157.48 152.4 0)
			(effects
				(font
					(size 1.27 1.27)
				)
			)
		)
		(property "Footprint" ""
			(at 157.48 148.59 0)
			(effects
				(font
					(size 1.27 1.27)
				)
				(hide yes)
			)
		)
		(property "Datasheet" ""
			(at 157.48 148.59 0)
			(effects
				(font
					(size 1.27 1.27)
				)
				(hide yes)
			)
		)
		(property "Description" ""
			(at 157.48 148.59 0)
			(effects
				(font
					(size 1.27 1.27)
				)
				(hide yes)
			)
		)
		(property "Author" "Antmicro"
			(at 166.37 156.21 0)
			(effects
				(font
					(size 1.27 1.27)
					(thickness 0.15)
				)
				(justify left bottom)
				(hide yes)
			)
		)
		(property "License" "Apache-2.0"
			(at 166.37 158.75 0)
			(effects
				(font
					(size 1.27 1.27)
					(thickness 0.15)
				)
				(justify left bottom)
				(hide yes)
			)
		)
		(pin "1"
		)
		(instances
			(project "thunderbolt-to-10gbe-adapter"
				(path ""
					(reference "#PWR097")
					(unit 1)
				)
			)
		)
	)
	(symbol
		(lib_id "antmicropower:GND")
		(at 240.03 80.01 0)
		(unit 1)
		(exclude_from_sim no)
		(in_bom yes)
		(on_board yes)
		(dnp no)
		(property "Reference" "#PWR0125"
			(at 240.03 86.36 0)
			(effects
				(font
					(size 1.27 1.27)
				)
				(hide yes)
			)
		)
		(property "Value" "GND"
			(at 240.03 83.82 0)
			(effects
				(font
					(size 1.27 1.27)
				)
			)
		)
		(property "Footprint" ""
			(at 240.03 80.01 0)
			(effects
				(font
					(size 1.27 1.27)
				)
				(hide yes)
			)
		)
		(property "Datasheet" ""
			(at 240.03 80.01 0)
			(effects
				(font
					(size 1.27 1.27)
				)
				(hide yes)
			)
		)
		(property "Description" ""
			(at 240.03 80.01 0)
			(effects
				(font
					(size 1.27 1.27)
				)
				(hide yes)
			)
		)
		(property "Author" "Antmicro"
			(at 248.92 87.63 0)
			(effects
				(font
					(size 1.27 1.27)
					(thickness 0.15)
				)
				(justify left bottom)
				(hide yes)
			)
		)
		(property "License" "Apache-2.0"
			(at 248.92 90.17 0)
			(effects
				(font
					(size 1.27 1.27)
					(thickness 0.15)
				)
				(justify left bottom)
				(hide yes)
			)
		)
		(pin "1"
		)
		(instances
			(project "thunderbolt-to-10gbe-adapter"
				(path ""
					(reference "#PWR0125")
					(unit 1)
				)
			)
		)
	)
	(symbol
		(lib_id "antmicroCapacitors0402:C_10u_0402")
		(at 246.38 165.1 90)
		(unit 1)
		(exclude_from_sim no)
		(in_bom yes)
		(on_board yes)
		(dnp no)
		(fields_autoplaced yes)
		(property "Reference" "C90"
			(at 247.015 160.655 90)
			(effects
				(font
					(size 1.27 1.27)
					(thickness 0.15)
				)
				(justify right)
			)
		)
		(property "Value" "C_10u_0402"
			(at 256.54 144.78 0)
			(effects
				(font
					(size 1.27 1.27)
					(thickness 0.15)
				)
				(justify left bottom)
				(hide yes)
			)
		)
		(property "Footprint" "antmicro-footprints:C_0402_1005Metric"
			(at 259.08 144.78 0)
			(effects
				(font
					(size 1.27 1.27)
					(thickness 0.15)
				)
				(justify left bottom)
				(hide yes)
			)
		)
		(property "Datasheet" "https://www.yageo.com/en/Chart/Download/pdf/CC0402MRX5R5BB106"
			(at 261.62 144.78 0)
			(effects
				(font
					(size 1.27 1.27)
					(thickness 0.15)
				)
				(justify left bottom)
				(hide yes)
			)
		)
		(property "Description" "SMD Multilayer Ceramic Capacitor, 10 µF, 6.3 V, 0402 [1005 Metric], ± 20%, X5R, CC Series"
			(at 246.38 165.1 0)
			(effects
				(font
					(size 1.27 1.27)
				)
				(hide yes)
			)
		)
		(property "MPN" "CC0402MRX5R5BB106"
			(at 264.16 144.78 0)
			(effects
				(font
					(size 1.27 1.27)
					(thickness 0.15)
				)
				(justify left bottom)
				(hide yes)
			)
		)
		(property "Manufacturer" "YAGEO"
			(at 266.7 144.78 0)
			(effects
				(font
					(size 1.27 1.27)
					(thickness 0.15)
				)
				(justify left bottom)
				(hide yes)
			)
		)
		(property "License" "Apache-2.0"
			(at 269.24 144.78 0)
			(effects
				(font
					(size 1.27 1.27)
					(thickness 0.15)
				)
				(justify left bottom)
				(hide yes)
			)
		)
		(property "Val" "10u"
			(at 247.015 164.465 90)
			(effects
				(font
					(size 1.27 1.27)
					(thickness 0.15)
				)
				(justify right)
			)
		)
		(property "Voltage" ""
			(at 274.32 144.78 0)
			(effects
				(font
					(size 1.27 1.27)
				)
				(justify left bottom)
				(hide yes)
			)
		)
		(property "Dielectric" ""
			(at 276.86 144.78 0)
			(effects
				(font
					(size 1.27 1.27)
				)
				(justify left bottom)
				(hide yes)
			)
		)
		(property "Author" "Antmicro"
			(at 271.78 144.78 0)
			(effects
				(font
					(size 1.27 1.27)
					(thickness 0.15)
				)
				(justify left bottom)
				(hide yes)
			)
		)
		(pin "1"
		)
		(pin "2"
		)
		(instances
			(project "thunderbolt-to-10gbe-adapter"
				(path ""
					(reference "C90")
					(unit 1)
				)
			)
		)
	)
	(symbol
		(lib_id "antmicroCapacitors0402:C_1u_0402")
		(at 226.06 111.76 270)
		(mirror x)
		(unit 1)
		(exclude_from_sim no)
		(in_bom yes)
		(on_board yes)
		(dnp no)
		(property "Reference" "C73"
			(at 223.52 107.9436 90)
			(effects
				(font
					(size 1.27 1.27)
					(thickness 0.15)
				)
				(justify right)
			)
		)
		(property "Value" "C_1u_0402"
			(at 215.9 91.44 0)
			(effects
				(font
					(size 1.27 1.27)
					(thickness 0.15)
				)
				(justify left bottom)
				(hide yes)
			)
		)
		(property "Footprint" "antmicro-footprints:C_0402_1005Metric"
			(at 213.36 91.44 0)
			(effects
				(font
					(size 1.27 1.27)
					(thickness 0.15)
				)
				(justify left bottom)
				(hide yes)
			)
		)
		(property "Datasheet" "https://product.tdk.com/en/search/capacitor/ceramic/mlcc/info?part_no=C1005X6S1A105K050BC"
			(at 210.82 91.44 0)
			(effects
				(font
					(size 1.27 1.27)
					(thickness 0.15)
				)
				(justify left bottom)
				(hide yes)
			)
		)
		(property "Description" "SMD Multilayer Ceramic Capacitor, 1 µF, 10 V, 0402 [1005 Metric], ± 10%, X6S, C"
			(at 226.06 111.76 0)
			(effects
				(font
					(size 1.27 1.27)
				)
				(hide yes)
			)
		)
		(property "MPN" "C1005X6S1A105K050BC"
			(at 208.28 91.44 0)
			(effects
				(font
					(size 1.27 1.27)
					(thickness 0.15)
				)
				(justify left bottom)
				(hide yes)
			)
		)
		(property "Manufacturer" "TDK"
			(at 205.74 91.44 0)
			(effects
				(font
					(size 1.27 1.27)
					(thickness 0.15)
				)
				(justify left bottom)
				(hide yes)
			)
		)
		(property "License" "Apache-2.0"
			(at 203.2 91.44 0)
			(effects
				(font
					(size 1.27 1.27)
					(thickness 0.15)
				)
				(justify left bottom)
				(hide yes)
			)
		)
		(property "Val" "1u"
			(at 223.52 110.4836 90)
			(effects
				(font
					(size 1.27 1.27)
					(thickness 0.15)
				)
				(justify right)
			)
		)
		(property "Voltage" ""
			(at 198.12 91.44 0)
			(effects
				(font
					(size 1.27 1.27)
				)
				(justify left bottom)
				(hide yes)
			)
		)
		(property "Dielectric" ""
			(at 195.58 91.44 0)
			(effects
				(font
					(size 1.27 1.27)
				)
				(justify left bottom)
				(hide yes)
			)
		)
		(property "Author" "Antmicro"
			(at 200.66 91.44 0)
			(effects
				(font
					(size 1.27 1.27)
					(thickness 0.15)
				)
				(justify left bottom)
				(hide yes)
			)
		)
		(pin "1"
		)
		(pin "2"
		)
		(instances
			(project "thunderbolt-to-10gbe-adapter"
				(path ""
					(reference "C73")
					(unit 1)
				)
			)
		)
	)
	(symbol
		(lib_id "antmicropower:GND")
		(at 262.89 168.91 0)
		(unit 1)
		(exclude_from_sim no)
		(in_bom yes)
		(on_board yes)
		(dnp no)
		(property "Reference" "#PWR0135"
			(at 262.89 175.26 0)
			(effects
				(font
					(size 1.27 1.27)
				)
				(hide yes)
			)
		)
		(property "Value" "GND"
			(at 262.89 172.72 0)
			(effects
				(font
					(size 1.27 1.27)
				)
			)
		)
		(property "Footprint" ""
			(at 262.89 168.91 0)
			(effects
				(font
					(size 1.27 1.27)
				)
				(hide yes)
			)
		)
		(property "Datasheet" ""
			(at 262.89 168.91 0)
			(effects
				(font
					(size 1.27 1.27)
				)
				(hide yes)
			)
		)
		(property "Description" ""
			(at 262.89 168.91 0)
			(effects
				(font
					(size 1.27 1.27)
				)
				(hide yes)
			)
		)
		(property "Author" "Antmicro"
			(at 271.78 176.53 0)
			(effects
				(font
					(size 1.27 1.27)
					(thickness 0.15)
				)
				(justify left bottom)
				(hide yes)
			)
		)
		(property "License" "Apache-2.0"
			(at 271.78 179.07 0)
			(effects
				(font
					(size 1.27 1.27)
					(thickness 0.15)
				)
				(justify left bottom)
				(hide yes)
			)
		)
		(pin "1"
		)
		(instances
			(project "thunderbolt-to-10gbe-adapter"
				(path ""
					(reference "#PWR0135")
					(unit 1)
				)
			)
		)
	)
	(symbol
		(lib_id "antmicropower:GND")
		(at 233.68 80.01 0)
		(unit 1)
		(exclude_from_sim no)
		(in_bom yes)
		(on_board yes)
		(dnp no)
		(property "Reference" "#PWR0120"
			(at 233.68 86.36 0)
			(effects
				(font
					(size 1.27 1.27)
				)
				(hide yes)
			)
		)
		(property "Value" "GND"
			(at 233.68 83.82 0)
			(effects
				(font
					(size 1.27 1.27)
				)
			)
		)
		(property "Footprint" ""
			(at 233.68 80.01 0)
			(effects
				(font
					(size 1.27 1.27)
				)
				(hide yes)
			)
		)
		(property "Datasheet" ""
			(at 233.68 80.01 0)
			(effects
				(font
					(size 1.27 1.27)
				)
				(hide yes)
			)
		)
		(property "Description" ""
			(at 233.68 80.01 0)
			(effects
				(font
					(size 1.27 1.27)
				)
				(hide yes)
			)
		)
		(property "Author" "Antmicro"
			(at 242.57 87.63 0)
			(effects
				(font
					(size 1.27 1.27)
					(thickness 0.15)
				)
				(justify left bottom)
				(hide yes)
			)
		)
		(property "License" "Apache-2.0"
			(at 242.57 90.17 0)
			(effects
				(font
					(size 1.27 1.27)
					(thickness 0.15)
				)
				(justify left bottom)
				(hide yes)
			)
		)
		(pin "1"
		)
		(instances
			(project "thunderbolt-to-10gbe-adapter"
				(path ""
					(reference "#PWR0120")
					(unit 1)
				)
			)
		)
	)
	(symbol
		(lib_id "antmicropower:GND")
		(at 246.38 80.01 0)
		(unit 1)
		(exclude_from_sim no)
		(in_bom yes)
		(on_board yes)
		(dnp no)
		(property "Reference" "#PWR0132"
			(at 246.38 86.36 0)
			(effects
				(font
					(size 1.27 1.27)
				)
				(hide yes)
			)
		)
		(property "Value" "GND"
			(at 246.38 83.82 0)
			(effects
				(font
					(size 1.27 1.27)
				)
			)
		)
		(property "Footprint" ""
			(at 246.38 80.01 0)
			(effects
				(font
					(size 1.27 1.27)
				)
				(hide yes)
			)
		)
		(property "Datasheet" ""
			(at 246.38 80.01 0)
			(effects
				(font
					(size 1.27 1.27)
				)
				(hide yes)
			)
		)
		(property "Description" ""
			(at 246.38 80.01 0)
			(effects
				(font
					(size 1.27 1.27)
				)
				(hide yes)
			)
		)
		(property "Author" "Antmicro"
			(at 255.27 87.63 0)
			(effects
				(font
					(size 1.27 1.27)
					(thickness 0.15)
				)
				(justify left bottom)
				(hide yes)
			)
		)
		(property "License" "Apache-2.0"
			(at 255.27 90.17 0)
			(effects
				(font
					(size 1.27 1.27)
					(thickness 0.15)
				)
				(justify left bottom)
				(hide yes)
			)
		)
		(pin "1"
		)
		(instances
			(project "thunderbolt-to-10gbe-adapter"
				(path ""
					(reference "#PWR0132")
					(unit 1)
				)
			)
		)
	)
	(symbol
		(lib_id "antmicroCapacitors0402:C_10u_0402")
		(at 259.08 110.49 90)
		(unit 1)
		(exclude_from_sim no)
		(in_bom yes)
		(on_board yes)
		(dnp no)
		(fields_autoplaced yes)
		(property "Reference" "C97"
			(at 259.715 106.045 90)
			(effects
				(font
					(size 1.27 1.27)
					(thickness 0.15)
				)
				(justify right)
			)
		)
		(property "Value" "C_10u_0402"
			(at 269.24 90.17 0)
			(effects
				(font
					(size 1.27 1.27)
					(thickness 0.15)
				)
				(justify left bottom)
				(hide yes)
			)
		)
		(property "Footprint" "antmicro-footprints:C_0402_1005Metric"
			(at 271.78 90.17 0)
			(effects
				(font
					(size 1.27 1.27)
					(thickness 0.15)
				)
				(justify left bottom)
				(hide yes)
			)
		)
		(property "Datasheet" "https://www.yageo.com/en/Chart/Download/pdf/CC0402MRX5R5BB106"
			(at 274.32 90.17 0)
			(effects
				(font
					(size 1.27 1.27)
					(thickness 0.15)
				)
				(justify left bottom)
				(hide yes)
			)
		)
		(property "Description" "SMD Multilayer Ceramic Capacitor, 10 µF, 6.3 V, 0402 [1005 Metric], ± 20%, X5R, CC Series"
			(at 259.08 110.49 0)
			(effects
				(font
					(size 1.27 1.27)
				)
				(hide yes)
			)
		)
		(property "MPN" "CC0402MRX5R5BB106"
			(at 276.86 90.17 0)
			(effects
				(font
					(size 1.27 1.27)
					(thickness 0.15)
				)
				(justify left bottom)
				(hide yes)
			)
		)
		(property "Manufacturer" "YAGEO"
			(at 279.4 90.17 0)
			(effects
				(font
					(size 1.27 1.27)
					(thickness 0.15)
				)
				(justify left bottom)
				(hide yes)
			)
		)
		(property "License" "Apache-2.0"
			(at 281.94 90.17 0)
			(effects
				(font
					(size 1.27 1.27)
					(thickness 0.15)
				)
				(justify left bottom)
				(hide yes)
			)
		)
		(property "Val" "10u"
			(at 259.715 109.855 90)
			(effects
				(font
					(size 1.27 1.27)
					(thickness 0.15)
				)
				(justify right)
			)
		)
		(property "Voltage" ""
			(at 287.02 90.17 0)
			(effects
				(font
					(size 1.27 1.27)
				)
				(justify left bottom)
				(hide yes)
			)
		)
		(property "Dielectric" ""
			(at 289.56 90.17 0)
			(effects
				(font
					(size 1.27 1.27)
				)
				(justify left bottom)
				(hide yes)
			)
		)
		(property "Author" "Antmicro"
			(at 284.48 90.17 0)
			(effects
				(font
					(size 1.27 1.27)
					(thickness 0.15)
				)
				(justify left bottom)
				(hide yes)
			)
		)
		(pin "1"
		)
		(pin "2"
		)
		(instances
			(project "thunderbolt-to-10gbe-adapter"
				(path ""
					(reference "C97")
					(unit 1)
				)
			)
		)
	)
	(symbol
		(lib_id "antmicroResistors0402:R_100k_0402")
		(at 243.84 224.79 90)
		(unit 1)
		(exclude_from_sim no)
		(in_bom yes)
		(on_board yes)
		(dnp no)
		(property "Reference" "R73"
			(at 245.11 220.98 90)
			(effects
				(font
					(size 1.27 1.27)
					(thickness 0.15)
				)
				(justify right)
			)
		)
		(property "Value" "R_100k_0402"
			(at 256.54 204.47 0)
			(effects
				(font
					(size 1.27 1.27)
					(thickness 0.15)
				)
				(justify left bottom)
				(hide yes)
			)
		)
		(property "Footprint" "antmicro-footprints:R_0402_1005Metric"
			(at 259.08 204.47 0)
			(effects
				(font
					(size 1.27 1.27)
					(thickness 0.15)
				)
				(justify left bottom)
				(hide yes)
			)
		)
		(property "Datasheet" "https://www.bourns.com/docs/product-datasheets/cr.pdf"
			(at 261.62 204.47 0)
			(effects
				(font
					(size 1.27 1.27)
					(thickness 0.15)
				)
				(justify left bottom)
				(hide yes)
			)
		)
		(property "Description" "SMD Chip Resistor, 100 kohm, ± 1%, 62.5 mW, 0402 [1005 Metric], Thick Film, General Purpose"
			(at 243.84 224.79 0)
			(effects
				(font
					(size 1.27 1.27)
				)
				(hide yes)
			)
		)
		(property "MPN" "CR0402-FX-1003GLF"
			(at 264.16 204.47 0)
			(effects
				(font
					(size 1.27 1.27)
					(thickness 0.15)
				)
				(justify left bottom)
				(hide yes)
			)
		)
		(property "Manufacturer" "Bourns"
			(at 266.7 204.47 0)
			(effects
				(font
					(size 1.27 1.27)
					(thickness 0.15)
				)
				(justify left bottom)
				(hide yes)
			)
		)
		(property "License" "Apache-2.0"
			(at 269.24 204.47 0)
			(effects
				(font
					(size 1.27 1.27)
					(thickness 0.15)
				)
				(justify left bottom)
				(hide yes)
			)
		)
		(property "Val" "100k"
			(at 245.11 223.52 90)
			(effects
				(font
					(size 1.27 1.27)
					(thickness 0.15)
				)
				(justify right)
			)
		)
		(property "Tolerance" "1%"
			(at 254 204.47 0)
			(effects
				(font
					(size 1.27 1.27)
				)
				(justify left bottom)
				(hide yes)
			)
		)
		(property "Author" "Antmicro"
			(at 271.78 204.47 0)
			(effects
				(font
					(size 1.27 1.27)
					(thickness 0.15)
				)
				(justify left bottom)
				(hide yes)
			)
		)
		(pin "1"
		)
		(pin "2"
		)
		(instances
			(project "thunderbolt-to-10gbe-adapter"
				(path ""
					(reference "R73")
					(unit 1)
				)
			)
		)
	)
	(symbol
		(lib_id "antmicropower:GND")
		(at 142.24 96.52 0)
		(unit 1)
		(exclude_from_sim no)
		(in_bom yes)
		(on_board yes)
		(dnp no)
		(property "Reference" "#PWR083"
			(at 142.24 102.87 0)
			(effects
				(font
					(size 1.27 1.27)
				)
				(hide yes)
			)
		)
		(property "Value" "GND"
			(at 142.24 100.33 0)
			(effects
				(font
					(size 1.27 1.27)
				)
			)
		)
		(property "Footprint" ""
			(at 142.24 96.52 0)
			(effects
				(font
					(size 1.27 1.27)
				)
				(hide yes)
			)
		)
		(property "Datasheet" ""
			(at 142.24 96.52 0)
			(effects
				(font
					(size 1.27 1.27)
				)
				(hide yes)
			)
		)
		(property "Description" ""
			(at 142.24 96.52 0)
			(effects
				(font
					(size 1.27 1.27)
				)
				(hide yes)
			)
		)
		(property "Author" "Antmicro"
			(at 151.13 104.14 0)
			(effects
				(font
					(size 1.27 1.27)
					(thickness 0.15)
				)
				(justify left bottom)
				(hide yes)
			)
		)
		(property "License" "Apache-2.0"
			(at 151.13 106.68 0)
			(effects
				(font
					(size 1.27 1.27)
					(thickness 0.15)
				)
				(justify left bottom)
				(hide yes)
			)
		)
		(pin "1"
		)
		(instances
			(project "thunderbolt-to-10gbe-adapter"
				(path ""
					(reference "#PWR083")
					(unit 1)
				)
			)
		)
	)
	(symbol
		(lib_id "antmicroCapacitors0402:C_10u_0402")
		(at 271.78 78.74 90)
		(unit 1)
		(exclude_from_sim no)
		(in_bom yes)
		(on_board yes)
		(dnp no)
		(property "Reference" "C102"
			(at 272.415 74.295 90)
			(effects
				(font
					(size 1.27 1.27)
					(thickness 0.15)
				)
				(justify right)
			)
		)
		(property "Value" "C_10u_0402"
			(at 281.94 58.42 0)
			(effects
				(font
					(size 1.27 1.27)
					(thickness 0.15)
				)
				(justify left bottom)
				(hide yes)
			)
		)
		(property "Footprint" "antmicro-footprints:C_0402_1005Metric"
			(at 284.48 58.42 0)
			(effects
				(font
					(size 1.27 1.27)
					(thickness 0.15)
				)
				(justify left bottom)
				(hide yes)
			)
		)
		(property "Datasheet" "https://www.yageo.com/en/Chart/Download/pdf/CC0402MRX5R5BB106"
			(at 287.02 58.42 0)
			(effects
				(font
					(size 1.27 1.27)
					(thickness 0.15)
				)
				(justify left bottom)
				(hide yes)
			)
		)
		(property "Description" "SMD Multilayer Ceramic Capacitor, 10 µF, 6.3 V, 0402 [1005 Metric], ± 20%, X5R, CC Series"
			(at 271.78 78.74 0)
			(effects
				(font
					(size 1.27 1.27)
				)
				(hide yes)
			)
		)
		(property "MPN" "CC0402MRX5R5BB106"
			(at 289.56 58.42 0)
			(effects
				(font
					(size 1.27 1.27)
					(thickness 0.15)
				)
				(justify left bottom)
				(hide yes)
			)
		)
		(property "Manufacturer" "YAGEO"
			(at 292.1 58.42 0)
			(effects
				(font
					(size 1.27 1.27)
					(thickness 0.15)
				)
				(justify left bottom)
				(hide yes)
			)
		)
		(property "License" "Apache-2.0"
			(at 294.64 58.42 0)
			(effects
				(font
					(size 1.27 1.27)
					(thickness 0.15)
				)
				(justify left bottom)
				(hide yes)
			)
		)
		(property "Val" "10u"
			(at 272.415 78.105 90)
			(effects
				(font
					(size 1.27 1.27)
					(thickness 0.15)
				)
				(justify right)
			)
		)
		(property "Voltage" ""
			(at 299.72 58.42 0)
			(effects
				(font
					(size 1.27 1.27)
				)
				(justify left bottom)
				(hide yes)
			)
		)
		(property "Dielectric" ""
			(at 302.26 58.42 0)
			(effects
				(font
					(size 1.27 1.27)
				)
				(justify left bottom)
				(hide yes)
			)
		)
		(property "Author" "Antmicro"
			(at 297.18 58.42 0)
			(effects
				(font
					(size 1.27 1.27)
					(thickness 0.15)
				)
				(justify left bottom)
				(hide yes)
			)
		)
		(pin "1"
		)
		(pin "2"
		)
		(instances
			(project "thunderbolt-to-10gbe-adapter"
				(path ""
					(reference "C102")
					(unit 1)
				)
			)
		)
	)
	(symbol
		(lib_id "antmicroResistors0402:R_47k_0402")
		(at 281.94 153.67 0)
		(unit 1)
		(exclude_from_sim no)
		(in_bom yes)
		(on_board yes)
		(dnp no)
		(fields_autoplaced yes)
		(property "Reference" "R78"
			(at 284.48 147.32 0)
			(effects
				(font
					(size 1.27 1.27)
					(thickness 0.15)
				)
			)
		)
		(property "Value" "R_47k_0402"
			(at 302.26 166.37 0)
			(effects
				(font
					(size 1.27 1.27)
					(thickness 0.15)
				)
				(justify left bottom)
				(hide yes)
			)
		)
		(property "Footprint" "antmicro-footprints:R_0402_1005Metric"
			(at 302.26 168.91 0)
			(effects
				(font
					(size 1.27 1.27)
					(thickness 0.15)
				)
				(justify left bottom)
				(hide yes)
			)
		)
		(property "Datasheet" "https://www.bourns.com/docs/product-datasheets/cr.pdf"
			(at 302.26 171.45 0)
			(effects
				(font
					(size 1.27 1.27)
					(thickness 0.15)
				)
				(justify left bottom)
				(hide yes)
			)
		)
		(property "Description" "SMD Chip Resistor, 47 kohm, ± 1%, 62.5 mW, 0402 [1005 Metric], Thick Film, General Purpose"
			(at 281.94 153.67 0)
			(effects
				(font
					(size 1.27 1.27)
				)
				(hide yes)
			)
		)
		(property "MPN" "CR0402-FX-4702GLF"
			(at 302.26 173.99 0)
			(effects
				(font
					(size 1.27 1.27)
					(thickness 0.15)
				)
				(justify left bottom)
				(hide yes)
			)
		)
		(property "Manufacturer" "Bourns"
			(at 302.26 176.53 0)
			(effects
				(font
					(size 1.27 1.27)
					(thickness 0.15)
				)
				(justify left bottom)
				(hide yes)
			)
		)
		(property "License" "Apache-2.0"
			(at 302.26 179.07 0)
			(effects
				(font
					(size 1.27 1.27)
					(thickness 0.15)
				)
				(justify left bottom)
				(hide yes)
			)
		)
		(property "Author" "Antmicro"
			(at 302.26 181.61 0)
			(effects
				(font
					(size 1.27 1.27)
					(thickness 0.15)
				)
				(justify left bottom)
				(hide yes)
			)
		)
		(property "Val" "47k"
			(at 284.48 149.86 0)
			(effects
				(font
					(size 1.27 1.27)
					(thickness 0.15)
				)
			)
		)
		(property "Tolerance" "1%"
			(at 302.26 163.83 0)
			(effects
				(font
					(size 1.27 1.27)
				)
				(justify left bottom)
				(hide yes)
			)
		)
		(pin "1"
		)
		(pin "2"
		)
		(instances
			(project "thunderbolt-to-10gbe-adapter"
				(path ""
					(reference "R78")
					(unit 1)
				)
			)
		)
	)
	(symbol
		(lib_id "antmicropower:+3V3")
		(at 138.43 213.36 0)
		(unit 1)
		(exclude_from_sim no)
		(in_bom yes)
		(on_board yes)
		(dnp no)
		(property "Reference" "#PWR081"
			(at 153.67 213.36 0)
			(effects
				(font
					(size 1.27 1.27)
					(thickness 0.15)
				)
				(justify left bottom)
				(hide yes)
			)
		)
		(property "Value" "+3V3_TB"
			(at 138.43 209.55 0)
			(effects
				(font
					(size 1.27 1.27)
					(thickness 0.15)
				)
			)
		)
		(property "Footprint" ""
			(at 153.67 220.98 0)
			(effects
				(font
					(size 1.27 1.27)
					(thickness 0.15)
				)
				(justify left bottom)
				(hide yes)
			)
		)
		(property "Datasheet" ""
			(at 153.67 223.52 0)
			(effects
				(font
					(size 1.27 1.27)
					(thickness 0.15)
				)
				(justify left bottom)
				(hide yes)
			)
		)
		(property "Description" ""
			(at 153.67 226.06 0)
			(effects
				(font
					(size 1.27 1.27)
				)
				(justify left bottom)
				(hide yes)
			)
		)
		(property "Author" "Antmicro"
			(at 153.67 215.9 0)
			(effects
				(font
					(size 1.27 1.27)
					(thickness 0.15)
				)
				(justify left bottom)
				(hide yes)
			)
		)
		(property "License" "Apache-2.0"
			(at 153.67 218.44 0)
			(effects
				(font
					(size 1.27 1.27)
					(thickness 0.15)
				)
				(justify left bottom)
				(hide yes)
			)
		)
		(pin "1"
		)
		(instances
			(project "thunderbolt-to-10gbe-adapter"
				(path ""
					(reference "#PWR081")
					(unit 1)
				)
			)
		)
	)
	(symbol
		(lib_id "antmicropower:GND")
		(at 147.32 96.52 0)
		(unit 1)
		(exclude_from_sim no)
		(in_bom yes)
		(on_board yes)
		(dnp no)
		(property "Reference" "#PWR085"
			(at 147.32 102.87 0)
			(effects
				(font
					(size 1.27 1.27)
				)
				(hide yes)
			)
		)
		(property "Value" "GND"
			(at 147.32 100.33 0)
			(effects
				(font
					(size 1.27 1.27)
				)
			)
		)
		(property "Footprint" ""
			(at 147.32 96.52 0)
			(effects
				(font
					(size 1.27 1.27)
				)
				(hide yes)
			)
		)
		(property "Datasheet" ""
			(at 147.32 96.52 0)
			(effects
				(font
					(size 1.27 1.27)
				)
				(hide yes)
			)
		)
		(property "Description" ""
			(at 147.32 96.52 0)
			(effects
				(font
					(size 1.27 1.27)
				)
				(hide yes)
			)
		)
		(property "Author" "Antmicro"
			(at 156.21 104.14 0)
			(effects
				(font
					(size 1.27 1.27)
					(thickness 0.15)
				)
				(justify left bottom)
				(hide yes)
			)
		)
		(property "License" "Apache-2.0"
			(at 156.21 106.68 0)
			(effects
				(font
					(size 1.27 1.27)
					(thickness 0.15)
				)
				(justify left bottom)
				(hide yes)
			)
		)
		(pin "1"
		)
		(instances
			(project "thunderbolt-to-10gbe-adapter"
				(path ""
					(reference "#PWR085")
					(unit 1)
				)
			)
		)
	)
	(symbol
		(lib_id "antmicropower:GND")
		(at 162.56 114.3 0)
		(unit 1)
		(exclude_from_sim no)
		(in_bom yes)
		(on_board yes)
		(dnp no)
		(property "Reference" "#PWR0100"
			(at 162.56 120.65 0)
			(effects
				(font
					(size 1.27 1.27)
				)
				(hide yes)
			)
		)
		(property "Value" "GND"
			(at 162.56 118.11 0)
			(effects
				(font
					(size 1.27 1.27)
				)
			)
		)
		(property "Footprint" ""
			(at 162.56 114.3 0)
			(effects
				(font
					(size 1.27 1.27)
				)
				(hide yes)
			)
		)
		(property "Datasheet" ""
			(at 162.56 114.3 0)
			(effects
				(font
					(size 1.27 1.27)
				)
				(hide yes)
			)
		)
		(property "Description" ""
			(at 162.56 114.3 0)
			(effects
				(font
					(size 1.27 1.27)
				)
				(hide yes)
			)
		)
		(property "Author" "Antmicro"
			(at 171.45 121.92 0)
			(effects
				(font
					(size 1.27 1.27)
					(thickness 0.15)
				)
				(justify left bottom)
				(hide yes)
			)
		)
		(property "License" "Apache-2.0"
			(at 171.45 124.46 0)
			(effects
				(font
					(size 1.27 1.27)
					(thickness 0.15)
				)
				(justify left bottom)
				(hide yes)
			)
		)
		(pin "1"
		)
		(instances
			(project "thunderbolt-to-10gbe-adapter"
				(path ""
					(reference "#PWR0100")
					(unit 1)
				)
			)
		)
	)
	(symbol
		(lib_id "antmicropower:GND")
		(at 157.48 96.52 0)
		(unit 1)
		(exclude_from_sim no)
		(in_bom yes)
		(on_board yes)
		(dnp no)
		(property "Reference" "#PWR094"
			(at 157.48 102.87 0)
			(effects
				(font
					(size 1.27 1.27)
				)
				(hide yes)
			)
		)
		(property "Value" "GND"
			(at 157.48 100.33 0)
			(effects
				(font
					(size 1.27 1.27)
				)
			)
		)
		(property "Footprint" ""
			(at 157.48 96.52 0)
			(effects
				(font
					(size 1.27 1.27)
				)
				(hide yes)
			)
		)
		(property "Datasheet" ""
			(at 157.48 96.52 0)
			(effects
				(font
					(size 1.27 1.27)
				)
				(hide yes)
			)
		)
		(property "Description" ""
			(at 157.48 96.52 0)
			(effects
				(font
					(size 1.27 1.27)
				)
				(hide yes)
			)
		)
		(property "Author" "Antmicro"
			(at 166.37 104.14 0)
			(effects
				(font
					(size 1.27 1.27)
					(thickness 0.15)
				)
				(justify left bottom)
				(hide yes)
			)
		)
		(property "License" "Apache-2.0"
			(at 166.37 106.68 0)
			(effects
				(font
					(size 1.27 1.27)
					(thickness 0.15)
				)
				(justify left bottom)
				(hide yes)
			)
		)
		(pin "1"
		)
		(instances
			(project "thunderbolt-to-10gbe-adapter"
				(path ""
					(reference "#PWR094")
					(unit 1)
				)
			)
		)
	)
	(symbol
		(lib_id "antmicropower:GND")
		(at 166.37 168.91 0)
		(unit 1)
		(exclude_from_sim no)
		(in_bom yes)
		(on_board yes)
		(dnp no)
		(property "Reference" "#PWR0103"
			(at 166.37 175.26 0)
			(effects
				(font
					(size 1.27 1.27)
				)
				(hide yes)
			)
		)
		(property "Value" "GND"
			(at 166.37 172.72 0)
			(effects
				(font
					(size 1.27 1.27)
				)
			)
		)
		(property "Footprint" ""
			(at 166.37 168.91 0)
			(effects
				(font
					(size 1.27 1.27)
				)
				(hide yes)
			)
		)
		(property "Datasheet" ""
			(at 166.37 168.91 0)
			(effects
				(font
					(size 1.27 1.27)
				)
				(hide yes)
			)
		)
		(property "Description" ""
			(at 166.37 168.91 0)
			(effects
				(font
					(size 1.27 1.27)
				)
				(hide yes)
			)
		)
		(property "Author" "Antmicro"
			(at 175.26 176.53 0)
			(effects
				(font
					(size 1.27 1.27)
					(thickness 0.15)
				)
				(justify left bottom)
				(hide yes)
			)
		)
		(property "License" "Apache-2.0"
			(at 175.26 179.07 0)
			(effects
				(font
					(size 1.27 1.27)
					(thickness 0.15)
				)
				(justify left bottom)
				(hide yes)
			)
		)
		(pin "1"
		)
		(instances
			(project "thunderbolt-to-10gbe-adapter"
				(path ""
					(reference "#PWR0103")
					(unit 1)
				)
			)
		)
	)
	(symbol
		(lib_id "antmicropower:GND")
		(at 226.06 113.03 0)
		(unit 1)
		(exclude_from_sim no)
		(in_bom yes)
		(on_board yes)
		(dnp no)
		(property "Reference" "#PWR0106"
			(at 226.06 119.38 0)
			(effects
				(font
					(size 1.27 1.27)
				)
				(hide yes)
			)
		)
		(property "Value" "GND"
			(at 226.06 116.84 0)
			(effects
				(font
					(size 1.27 1.27)
				)
			)
		)
		(property "Footprint" ""
			(at 226.06 113.03 0)
			(effects
				(font
					(size 1.27 1.27)
				)
				(hide yes)
			)
		)
		(property "Datasheet" ""
			(at 226.06 113.03 0)
			(effects
				(font
					(size 1.27 1.27)
				)
				(hide yes)
			)
		)
		(property "Description" ""
			(at 226.06 113.03 0)
			(effects
				(font
					(size 1.27 1.27)
				)
				(hide yes)
			)
		)
		(property "Author" "Antmicro"
			(at 234.95 120.65 0)
			(effects
				(font
					(size 1.27 1.27)
					(thickness 0.15)
				)
				(justify left bottom)
				(hide yes)
			)
		)
		(property "License" "Apache-2.0"
			(at 234.95 123.19 0)
			(effects
				(font
					(size 1.27 1.27)
					(thickness 0.15)
				)
				(justify left bottom)
				(hide yes)
			)
		)
		(pin "1"
		)
		(instances
			(project "thunderbolt-to-10gbe-adapter"
				(path ""
					(reference "#PWR0106")
					(unit 1)
				)
			)
		)
	)
	(symbol
		(lib_id "antmicropower:GND")
		(at 252.73 168.91 0)
		(unit 1)
		(exclude_from_sim no)
		(in_bom yes)
		(on_board yes)
		(dnp no)
		(property "Reference" "#PWR0129"
			(at 252.73 175.26 0)
			(effects
				(font
					(size 1.27 1.27)
				)
				(hide yes)
			)
		)
		(property "Value" "GND"
			(at 252.73 172.72 0)
			(effects
				(font
					(size 1.27 1.27)
				)
			)
		)
		(property "Footprint" ""
			(at 252.73 168.91 0)
			(effects
				(font
					(size 1.27 1.27)
				)
				(hide yes)
			)
		)
		(property "Datasheet" ""
			(at 252.73 168.91 0)
			(effects
				(font
					(size 1.27 1.27)
				)
				(hide yes)
			)
		)
		(property "Description" ""
			(at 252.73 168.91 0)
			(effects
				(font
					(size 1.27 1.27)
				)
				(hide yes)
			)
		)
		(property "Author" "Antmicro"
			(at 261.62 176.53 0)
			(effects
				(font
					(size 1.27 1.27)
					(thickness 0.15)
				)
				(justify left bottom)
				(hide yes)
			)
		)
		(property "License" "Apache-2.0"
			(at 261.62 179.07 0)
			(effects
				(font
					(size 1.27 1.27)
					(thickness 0.15)
				)
				(justify left bottom)
				(hide yes)
			)
		)
		(pin "1"
		)
		(instances
			(project "thunderbolt-to-10gbe-adapter"
				(path ""
					(reference "#PWR0129")
					(unit 1)
				)
			)
		)
	)
	(symbol
		(lib_id "antmicropower:GND")
		(at 162.56 132.08 0)
		(unit 1)
		(exclude_from_sim no)
		(in_bom yes)
		(on_board yes)
		(dnp no)
		(property "Reference" "#PWR0101"
			(at 162.56 138.43 0)
			(effects
				(font
					(size 1.27 1.27)
				)
				(hide yes)
			)
		)
		(property "Value" "GND"
			(at 162.56 135.89 0)
			(effects
				(font
					(size 1.27 1.27)
				)
			)
		)
		(property "Footprint" ""
			(at 162.56 132.08 0)
			(effects
				(font
					(size 1.27 1.27)
				)
				(hide yes)
			)
		)
		(property "Datasheet" ""
			(at 162.56 132.08 0)
			(effects
				(font
					(size 1.27 1.27)
				)
				(hide yes)
			)
		)
		(property "Description" ""
			(at 162.56 132.08 0)
			(effects
				(font
					(size 1.27 1.27)
				)
				(hide yes)
			)
		)
		(property "Author" "Antmicro"
			(at 171.45 139.7 0)
			(effects
				(font
					(size 1.27 1.27)
					(thickness 0.15)
				)
				(justify left bottom)
				(hide yes)
			)
		)
		(property "License" "Apache-2.0"
			(at 171.45 142.24 0)
			(effects
				(font
					(size 1.27 1.27)
					(thickness 0.15)
				)
				(justify left bottom)
				(hide yes)
			)
		)
		(pin "1"
		)
		(instances
			(project "thunderbolt-to-10gbe-adapter"
				(path ""
					(reference "#PWR0101")
					(unit 1)
				)
			)
		)
	)
	(symbol
		(lib_id "antmicroFixedInductors:L_1u_1.8A_0603")
		(at 261.62 102.87 0)
		(unit 1)
		(exclude_from_sim no)
		(in_bom yes)
		(on_board yes)
		(dnp no)
		(fields_autoplaced yes)
		(property "Reference" "L3"
			(at 264.16 97.79 0)
			(effects
				(font
					(size 1.27 1.27)
					(thickness 0.15)
				)
			)
		)
		(property "Value" "L_1u_1.8A_0603"
			(at 275.59 105.41 0)
			(effects
				(font
					(size 1.27 1.27)
					(thickness 0.15)
				)
				(justify left bottom)
				(hide yes)
			)
		)
		(property "Footprint" "antmicro-footprints:L_0603_1608Metric"
			(at 275.59 110.49 0)
			(effects
				(font
					(size 1.27 1.27)
					(thickness 0.15)
				)
				(justify left bottom)
				(hide yes)
			)
		)
		(property "Datasheet" "https://search.murata.co.jp/Ceramy/image/img/P02/JETE243A-0041.pdf"
			(at 275.59 113.03 0)
			(effects
				(font
					(size 1.27 1.27)
					(thickness 0.15)
				)
				(justify left bottom)
				(hide yes)
			)
		)
		(property "Description" "Power Inductor (SMT), 1 µH, 1.8 A, Shielded, 1.9 A, DFE Series, 0603 [1608 Metric]"
			(at 261.62 102.87 0)
			(effects
				(font
					(size 1.27 1.27)
				)
				(hide yes)
			)
		)
		(property "Val" "1u/1.8A"
			(at 264.16 100.33 0)
			(effects
				(font
					(size 1.27 1.27)
					(thickness 0.15)
				)
			)
		)
		(property "Manufacturer" "Murata"
			(at 275.59 115.57 0)
			(effects
				(font
					(size 1.27 1.27)
					(thickness 0.15)
				)
				(justify left bottom)
				(hide yes)
			)
		)
		(property "MPN" "DFE18SBN1R0ME0L"
			(at 275.59 118.11 0)
			(effects
				(font
					(size 1.27 1.27)
					(thickness 0.15)
				)
				(justify left bottom)
				(hide yes)
			)
		)
		(property "ISat" "1.9A"
			(at 275.59 119.38 0)
			(effects
				(font
					(size 1.27 1.27)
				)
				(justify left)
				(hide yes)
			)
		)
		(property "IMax" "1.8A"
			(at 275.59 123.19 0)
			(effects
				(font
					(size 1.27 1.27)
					(thickness 0.15)
				)
				(justify left bottom)
				(hide yes)
			)
		)
		(property "Size" "1.6x0.8"
			(at 275.59 125.73 0)
			(effects
				(font
					(size 1.27 1.27)
					(thickness 0.15)
				)
				(justify left bottom)
				(hide yes)
			)
		)
		(property "License" "Apache-2.0"
			(at 275.59 130.81 0)
			(effects
				(font
					(size 1.27 1.27)
					(thickness 0.15)
				)
				(justify left bottom)
				(hide yes)
			)
		)
		(property "Author" "Antmicro"
			(at 275.59 128.27 0)
			(effects
				(font
					(size 1.27 1.27)
					(thickness 0.15)
				)
				(justify left bottom)
				(hide yes)
			)
		)
		(pin "1"
		)
		(pin "2"
		)
		(instances
			(project "thunderbolt-to-10gbe-adapter"
				(path ""
					(reference "L3")
					(unit 1)
				)
			)
		)
	)
	(symbol
		(lib_id "antmicropower:GND")
		(at 157.48 114.3 0)
		(unit 1)
		(exclude_from_sim no)
		(in_bom yes)
		(on_board yes)
		(dnp no)
		(property "Reference" "#PWR095"
			(at 157.48 120.65 0)
			(effects
				(font
					(size 1.27 1.27)
				)
				(hide yes)
			)
		)
		(property "Value" "GND"
			(at 157.48 118.11 0)
			(effects
				(font
					(size 1.27 1.27)
				)
			)
		)
		(property "Footprint" ""
			(at 157.48 114.3 0)
			(effects
				(font
					(size 1.27 1.27)
				)
				(hide yes)
			)
		)
		(property "Datasheet" ""
			(at 157.48 114.3 0)
			(effects
				(font
					(size 1.27 1.27)
				)
				(hide yes)
			)
		)
		(property "Description" ""
			(at 157.48 114.3 0)
			(effects
				(font
					(size 1.27 1.27)
				)
				(hide yes)
			)
		)
		(property "Author" "Antmicro"
			(at 166.37 121.92 0)
			(effects
				(font
					(size 1.27 1.27)
					(thickness 0.15)
				)
				(justify left bottom)
				(hide yes)
			)
		)
		(property "License" "Apache-2.0"
			(at 166.37 124.46 0)
			(effects
				(font
					(size 1.27 1.27)
					(thickness 0.15)
				)
				(justify left bottom)
				(hide yes)
			)
		)
		(pin "1"
		)
		(instances
			(project "thunderbolt-to-10gbe-adapter"
				(path ""
					(reference "#PWR095")
					(unit 1)
				)
			)
		)
	)
	(symbol
		(lib_id "antmicroCapacitors0402:C_1u_0402")
		(at 227.33 95.25 90)
		(unit 1)
		(exclude_from_sim no)
		(in_bom yes)
		(on_board yes)
		(dnp no)
		(property "Reference" "C75"
			(at 227.965 90.805 90)
			(effects
				(font
					(size 1.27 1.27)
					(thickness 0.15)
				)
				(justify right)
			)
		)
		(property "Value" "C_1u_0402"
			(at 237.49 74.93 0)
			(effects
				(font
					(size 1.27 1.27)
					(thickness 0.15)
				)
				(justify left bottom)
				(hide yes)
			)
		)
		(property "Footprint" "antmicro-footprints:C_0402_1005Metric"
			(at 240.03 74.93 0)
			(effects
				(font
					(size 1.27 1.27)
					(thickness 0.15)
				)
				(justify left bottom)
				(hide yes)
			)
		)
		(property "Datasheet" "https://product.tdk.com/en/search/capacitor/ceramic/mlcc/info?part_no=C1005X6S1A105K050BC"
			(at 242.57 74.93 0)
			(effects
				(font
					(size 1.27 1.27)
					(thickness 0.15)
				)
				(justify left bottom)
				(hide yes)
			)
		)
		(property "Description" "SMD Multilayer Ceramic Capacitor, 1 µF, 10 V, 0402 [1005 Metric], ± 10%, X6S, C"
			(at 227.33 95.25 0)
			(effects
				(font
					(size 1.27 1.27)
				)
				(hide yes)
			)
		)
		(property "MPN" "C1005X6S1A105K050BC"
			(at 245.11 74.93 0)
			(effects
				(font
					(size 1.27 1.27)
					(thickness 0.15)
				)
				(justify left bottom)
				(hide yes)
			)
		)
		(property "Manufacturer" "TDK"
			(at 247.65 74.93 0)
			(effects
				(font
					(size 1.27 1.27)
					(thickness 0.15)
				)
				(justify left bottom)
				(hide yes)
			)
		)
		(property "License" "Apache-2.0"
			(at 250.19 74.93 0)
			(effects
				(font
					(size 1.27 1.27)
					(thickness 0.15)
				)
				(justify left bottom)
				(hide yes)
			)
		)
		(property "Val" "1u"
			(at 227.965 94.615 90)
			(effects
				(font
					(size 1.27 1.27)
					(thickness 0.15)
				)
				(justify right)
			)
		)
		(property "Voltage" ""
			(at 255.27 74.93 0)
			(effects
				(font
					(size 1.27 1.27)
				)
				(justify left bottom)
				(hide yes)
			)
		)
		(property "Dielectric" ""
			(at 257.81 74.93 0)
			(effects
				(font
					(size 1.27 1.27)
				)
				(justify left bottom)
				(hide yes)
			)
		)
		(property "Author" "Antmicro"
			(at 252.73 74.93 0)
			(effects
				(font
					(size 1.27 1.27)
					(thickness 0.15)
				)
				(justify left bottom)
				(hide yes)
			)
		)
		(pin "1"
		)
		(pin "2"
		)
		(instances
			(project "thunderbolt-to-10gbe-adapter"
				(path ""
					(reference "C75")
					(unit 1)
				)
			)
		)
	)
	(symbol
		(lib_id "antmicropower:GND")
		(at 254 227.33 0)
		(unit 1)
		(exclude_from_sim no)
		(in_bom yes)
		(on_board yes)
		(dnp no)
		(property "Reference" "#PWR0131"
			(at 254 233.68 0)
			(effects
				(font
					(size 1.27 1.27)
				)
				(hide yes)
			)
		)
		(property "Value" "GND"
			(at 254 231.14 0)
			(effects
				(font
					(size 1.27 1.27)
				)
			)
		)
		(property "Footprint" ""
			(at 254 227.33 0)
			(effects
				(font
					(size 1.27 1.27)
				)
				(hide yes)
			)
		)
		(property "Datasheet" ""
			(at 254 227.33 0)
			(effects
				(font
					(size 1.27 1.27)
				)
				(hide yes)
			)
		)
		(property "Description" ""
			(at 254 227.33 0)
			(effects
				(font
					(size 1.27 1.27)
				)
				(hide yes)
			)
		)
		(property "Author" "Antmicro"
			(at 262.89 234.95 0)
			(effects
				(font
					(size 1.27 1.27)
					(thickness 0.15)
				)
				(justify left bottom)
				(hide yes)
			)
		)
		(property "License" "Apache-2.0"
			(at 262.89 237.49 0)
			(effects
				(font
					(size 1.27 1.27)
					(thickness 0.15)
				)
				(justify left bottom)
				(hide yes)
			)
		)
		(pin "1"
		)
		(instances
			(project "thunderbolt-to-10gbe-adapter"
				(path ""
					(reference "#PWR0131")
					(unit 1)
				)
			)
		)
	)
	(symbol
		(lib_id "antmicroCapacitors0402:C_1u_0402")
		(at 240.03 128.27 90)
		(unit 1)
		(exclude_from_sim no)
		(in_bom yes)
		(on_board yes)
		(dnp no)
		(property "Reference" "C83"
			(at 240.665 123.825 90)
			(effects
				(font
					(size 1.27 1.27)
					(thickness 0.15)
				)
				(justify right)
			)
		)
		(property "Value" "C_1u_0402"
			(at 250.19 107.95 0)
			(effects
				(font
					(size 1.27 1.27)
					(thickness 0.15)
				)
				(justify left bottom)
				(hide yes)
			)
		)
		(property "Footprint" "antmicro-footprints:C_0402_1005Metric"
			(at 252.73 107.95 0)
			(effects
				(font
					(size 1.27 1.27)
					(thickness 0.15)
				)
				(justify left bottom)
				(hide yes)
			)
		)
		(property "Datasheet" "https://product.tdk.com/en/search/capacitor/ceramic/mlcc/info?part_no=C1005X6S1A105K050BC"
			(at 255.27 107.95 0)
			(effects
				(font
					(size 1.27 1.27)
					(thickness 0.15)
				)
				(justify left bottom)
				(hide yes)
			)
		)
		(property "Description" "SMD Multilayer Ceramic Capacitor, 1 µF, 10 V, 0402 [1005 Metric], ± 10%, X6S, C"
			(at 240.03 128.27 0)
			(effects
				(font
					(size 1.27 1.27)
				)
				(hide yes)
			)
		)
		(property "MPN" "C1005X6S1A105K050BC"
			(at 257.81 107.95 0)
			(effects
				(font
					(size 1.27 1.27)
					(thickness 0.15)
				)
				(justify left bottom)
				(hide yes)
			)
		)
		(property "Manufacturer" "TDK"
			(at 260.35 107.95 0)
			(effects
				(font
					(size 1.27 1.27)
					(thickness 0.15)
				)
				(justify left bottom)
				(hide yes)
			)
		)
		(property "License" "Apache-2.0"
			(at 262.89 107.95 0)
			(effects
				(font
					(size 1.27 1.27)
					(thickness 0.15)
				)
				(justify left bottom)
				(hide yes)
			)
		)
		(property "Val" "1u"
			(at 240.665 127.635 90)
			(effects
				(font
					(size 1.27 1.27)
					(thickness 0.15)
				)
				(justify right)
			)
		)
		(property "Voltage" ""
			(at 267.97 107.95 0)
			(effects
				(font
					(size 1.27 1.27)
				)
				(justify left bottom)
				(hide yes)
			)
		)
		(property "Dielectric" ""
			(at 270.51 107.95 0)
			(effects
				(font
					(size 1.27 1.27)
				)
				(justify left bottom)
				(hide yes)
			)
		)
		(property "Author" "Antmicro"
			(at 265.43 107.95 0)
			(effects
				(font
					(size 1.27 1.27)
					(thickness 0.15)
				)
				(justify left bottom)
				(hide yes)
			)
		)
		(pin "1"
		)
		(pin "2"
		)
		(instances
			(project "thunderbolt-to-10gbe-adapter"
				(path ""
					(reference "C83")
					(unit 1)
				)
			)
		)
	)
	(symbol
		(lib_id "antmicroCapacitors0603:C_22u_0603")
		(at 233.68 147.32 90)
		(unit 1)
		(exclude_from_sim no)
		(in_bom yes)
		(on_board yes)
		(dnp no)
		(property "Reference" "C80"
			(at 234.315 142.875 90)
			(effects
				(font
					(size 1.27 1.27)
					(thickness 0.15)
				)
				(justify right)
			)
		)
		(property "Value" "C_22u_0603"
			(at 243.84 127 0)
			(effects
				(font
					(size 1.27 1.27)
					(thickness 0.15)
				)
				(justify left bottom)
				(hide yes)
			)
		)
		(property "Footprint" "antmicro-footprints:C_0603_1608Metric"
			(at 246.38 127 0)
			(effects
				(font
					(size 1.27 1.27)
					(thickness 0.15)
				)
				(justify left bottom)
				(hide yes)
			)
		)
		(property "Datasheet" "https://www.murata.com/products/productdetail?partno=GRM188R60J226MEA0%23"
			(at 248.92 127 0)
			(effects
				(font
					(size 1.27 1.27)
					(thickness 0.15)
				)
				(justify left bottom)
				(hide yes)
			)
		)
		(property "Description" "SMD Multilayer Ceramic Capacitor, 22 µF, 6.3 V, 0603 [1608 Metric], ± 20%, X5R, GRM Series"
			(at 233.68 147.32 0)
			(effects
				(font
					(size 1.27 1.27)
				)
				(hide yes)
			)
		)
		(property "MPN" "GRM188R60J226MEA0D"
			(at 251.46 127 0)
			(effects
				(font
					(size 1.27 1.27)
					(thickness 0.15)
				)
				(justify left bottom)
				(hide yes)
			)
		)
		(property "Manufacturer" "Murata"
			(at 254 127 0)
			(effects
				(font
					(size 1.27 1.27)
					(thickness 0.15)
				)
				(justify left bottom)
				(hide yes)
			)
		)
		(property "License" "Apache-2.0"
			(at 256.54 127 0)
			(effects
				(font
					(size 1.27 1.27)
					(thickness 0.15)
				)
				(justify left bottom)
				(hide yes)
			)
		)
		(property "Val" "22u"
			(at 234.315 146.685 90)
			(effects
				(font
					(size 1.27 1.27)
					(thickness 0.15)
				)
				(justify right)
			)
		)
		(property "Voltage" ""
			(at 261.62 127 0)
			(effects
				(font
					(size 1.27 1.27)
				)
				(justify left bottom)
				(hide yes)
			)
		)
		(property "Dielectric" ""
			(at 264.16 127 0)
			(effects
				(font
					(size 1.27 1.27)
				)
				(justify left bottom)
				(hide yes)
			)
		)
		(property "Author" "Antmicro"
			(at 259.08 127 0)
			(effects
				(font
					(size 1.27 1.27)
					(thickness 0.15)
				)
				(justify left bottom)
				(hide yes)
			)
		)
		(pin "1"
		)
		(pin "2"
		)
		(instances
			(project "thunderbolt-to-10gbe-adapter"
				(path ""
					(reference "C80")
					(unit 1)
				)
			)
		)
	)
	(symbol
		(lib_id "antmicropower:GND")
		(at 252.73 129.54 0)
		(unit 1)
		(exclude_from_sim no)
		(in_bom yes)
		(on_board yes)
		(dnp no)
		(property "Reference" "#PWR0127"
			(at 252.73 135.89 0)
			(effects
				(font
					(size 1.27 1.27)
				)
				(hide yes)
			)
		)
		(property "Value" "GND"
			(at 252.73 133.35 0)
			(effects
				(font
					(size 1.27 1.27)
				)
			)
		)
		(property "Footprint" ""
			(at 252.73 129.54 0)
			(effects
				(font
					(size 1.27 1.27)
				)
				(hide yes)
			)
		)
		(property "Datasheet" ""
			(at 252.73 129.54 0)
			(effects
				(font
					(size 1.27 1.27)
				)
				(hide yes)
			)
		)
		(property "Description" ""
			(at 252.73 129.54 0)
			(effects
				(font
					(size 1.27 1.27)
				)
				(hide yes)
			)
		)
		(property "Author" "Antmicro"
			(at 261.62 137.16 0)
			(effects
				(font
					(size 1.27 1.27)
					(thickness 0.15)
				)
				(justify left bottom)
				(hide yes)
			)
		)
		(property "License" "Apache-2.0"
			(at 261.62 139.7 0)
			(effects
				(font
					(size 1.27 1.27)
					(thickness 0.15)
				)
				(justify left bottom)
				(hide yes)
			)
		)
		(pin "1"
		)
		(instances
			(project "thunderbolt-to-10gbe-adapter"
				(path ""
					(reference "#PWR0127")
					(unit 1)
				)
			)
		)
	)
	(symbol
		(lib_id "antmicroCapacitors0402:C_10u_0402")
		(at 252.73 165.1 90)
		(unit 1)
		(exclude_from_sim no)
		(in_bom yes)
		(on_board yes)
		(dnp no)
		(fields_autoplaced yes)
		(property "Reference" "C95"
			(at 253.365 160.655 90)
			(effects
				(font
					(size 1.27 1.27)
					(thickness 0.15)
				)
				(justify right)
			)
		)
		(property "Value" "C_10u_0402"
			(at 262.89 144.78 0)
			(effects
				(font
					(size 1.27 1.27)
					(thickness 0.15)
				)
				(justify left bottom)
				(hide yes)
			)
		)
		(property "Footprint" "antmicro-footprints:C_0402_1005Metric"
			(at 265.43 144.78 0)
			(effects
				(font
					(size 1.27 1.27)
					(thickness 0.15)
				)
				(justify left bottom)
				(hide yes)
			)
		)
		(property "Datasheet" "https://www.yageo.com/en/Chart/Download/pdf/CC0402MRX5R5BB106"
			(at 267.97 144.78 0)
			(effects
				(font
					(size 1.27 1.27)
					(thickness 0.15)
				)
				(justify left bottom)
				(hide yes)
			)
		)
		(property "Description" "SMD Multilayer Ceramic Capacitor, 10 µF, 6.3 V, 0402 [1005 Metric], ± 20%, X5R, CC Series"
			(at 252.73 165.1 0)
			(effects
				(font
					(size 1.27 1.27)
				)
				(hide yes)
			)
		)
		(property "MPN" "CC0402MRX5R5BB106"
			(at 270.51 144.78 0)
			(effects
				(font
					(size 1.27 1.27)
					(thickness 0.15)
				)
				(justify left bottom)
				(hide yes)
			)
		)
		(property "Manufacturer" "YAGEO"
			(at 273.05 144.78 0)
			(effects
				(font
					(size 1.27 1.27)
					(thickness 0.15)
				)
				(justify left bottom)
				(hide yes)
			)
		)
		(property "License" "Apache-2.0"
			(at 275.59 144.78 0)
			(effects
				(font
					(size 1.27 1.27)
					(thickness 0.15)
				)
				(justify left bottom)
				(hide yes)
			)
		)
		(property "Val" "10u"
			(at 253.365 164.465 90)
			(effects
				(font
					(size 1.27 1.27)
					(thickness 0.15)
				)
				(justify right)
			)
		)
		(property "Voltage" ""
			(at 280.67 144.78 0)
			(effects
				(font
					(size 1.27 1.27)
				)
				(justify left bottom)
				(hide yes)
			)
		)
		(property "Dielectric" ""
			(at 283.21 144.78 0)
			(effects
				(font
					(size 1.27 1.27)
				)
				(justify left bottom)
				(hide yes)
			)
		)
		(property "Author" "Antmicro"
			(at 278.13 144.78 0)
			(effects
				(font
					(size 1.27 1.27)
					(thickness 0.15)
				)
				(justify left bottom)
				(hide yes)
			)
		)
		(pin "1"
		)
		(pin "2"
		)
		(instances
			(project "thunderbolt-to-10gbe-adapter"
				(path ""
					(reference "C95")
					(unit 1)
				)
			)
		)
	)
	(symbol
		(lib_id "antmicropower:GND")
		(at 142.24 114.3 0)
		(unit 1)
		(exclude_from_sim no)
		(in_bom yes)
		(on_board yes)
		(dnp no)
		(property "Reference" "#PWR084"
			(at 142.24 120.65 0)
			(effects
				(font
					(size 1.27 1.27)
				)
				(hide yes)
			)
		)
		(property "Value" "GND"
			(at 142.24 118.11 0)
			(effects
				(font
					(size 1.27 1.27)
				)
			)
		)
		(property "Footprint" ""
			(at 142.24 114.3 0)
			(effects
				(font
					(size 1.27 1.27)
				)
				(hide yes)
			)
		)
		(property "Datasheet" ""
			(at 142.24 114.3 0)
			(effects
				(font
					(size 1.27 1.27)
				)
				(hide yes)
			)
		)
		(property "Description" ""
			(at 142.24 114.3 0)
			(effects
				(font
					(size 1.27 1.27)
				)
				(hide yes)
			)
		)
		(property "Author" "Antmicro"
			(at 151.13 121.92 0)
			(effects
				(font
					(size 1.27 1.27)
					(thickness 0.15)
				)
				(justify left bottom)
				(hide yes)
			)
		)
		(property "License" "Apache-2.0"
			(at 151.13 124.46 0)
			(effects
				(font
					(size 1.27 1.27)
					(thickness 0.15)
				)
				(justify left bottom)
				(hide yes)
			)
		)
		(pin "1"
		)
		(instances
			(project "thunderbolt-to-10gbe-adapter"
				(path ""
					(reference "#PWR084")
					(unit 1)
				)
			)
		)
	)
	(symbol
		(lib_id "antmicroOperationalAmplifiers:MCP6541_SOT23-5")
		(at 161.29 218.44 0)
		(unit 2)
		(exclude_from_sim no)
		(in_bom yes)
		(on_board yes)
		(dnp no)
		(fields_autoplaced yes)
		(property "Reference" "U6"
			(at 170.18 218.44 0)
			(effects
				(font
					(size 1.27 1.27)
					(thickness 0.15)
				)
				(justify left)
			)
		)
		(property "Value" "MCP6541_SOT23-5"
			(at 186.69 228.6 0)
			(effects
				(font
					(size 1.27 1.27)
					(thickness 0.15)
				)
				(justify left bottom)
				(hide yes)
			)
		)
		(property "Footprint" "antmicro-footprints:SOT-23-5"
			(at 186.69 231.14 0)
			(effects
				(font
					(size 1.27 1.27)
					(thickness 0.15)
				)
				(justify left bottom)
				(hide yes)
			)
		)
		(property "Datasheet" "https://www.farnell.com/datasheets/1641674.pdf"
			(at 186.69 233.68 0)
			(effects
				(font
					(size 1.27 1.27)
					(thickness 0.15)
				)
				(justify left bottom)
				(hide yes)
			)
		)
		(property "Description" "Push-Pull Output Comparator, 1,6V to 5.5V, SOT-23-5"
			(at 161.29 218.44 0)
			(effects
				(font
					(size 1.27 1.27)
				)
				(hide yes)
			)
		)
		(property "MPN" "MCP6541T-E/OT"
			(at 170.18 220.98 0)
			(effects
				(font
					(size 1.27 1.27)
					(thickness 0.15)
				)
				(justify left)
			)
		)
		(property "Manufacturer" "Microchip Technology"
			(at 186.69 236.22 0)
			(effects
				(font
					(size 1.27 1.27)
					(thickness 0.15)
				)
				(justify left bottom)
				(hide yes)
			)
		)
		(property "Author" "Antmicro"
			(at 186.69 238.76 0)
			(effects
				(font
					(size 1.27 1.27)
					(thickness 0.15)
				)
				(justify left bottom)
				(hide yes)
			)
		)
		(property "License" "Apache-2.0"
			(at 186.69 241.3 0)
			(effects
				(font
					(size 1.27 1.27)
					(thickness 0.15)
				)
				(justify left bottom)
				(hide yes)
			)
		)
		(pin "1"
		)
		(pin "3"
		)
		(pin "4"
		)
		(pin "2"
		)
		(pin "5"
		)
		(instances
			(project "thunderbolt-to-10gbe-adapter"
				(path ""
					(reference "U6")
					(unit 2)
				)
			)
		)
	)
	(symbol
		(lib_id "antmicropower:GND")
		(at 162.56 148.59 0)
		(unit 1)
		(exclude_from_sim no)
		(in_bom yes)
		(on_board yes)
		(dnp no)
		(property "Reference" "#PWR0102"
			(at 162.56 154.94 0)
			(effects
				(font
					(size 1.27 1.27)
				)
				(hide yes)
			)
		)
		(property "Value" "GND"
			(at 162.56 152.4 0)
			(effects
				(font
					(size 1.27 1.27)
				)
			)
		)
		(property "Footprint" ""
			(at 162.56 148.59 0)
			(effects
				(font
					(size 1.27 1.27)
				)
				(hide yes)
			)
		)
		(property "Datasheet" ""
			(at 162.56 148.59 0)
			(effects
				(font
					(size 1.27 1.27)
				)
				(hide yes)
			)
		)
		(property "Description" ""
			(at 162.56 148.59 0)
			(effects
				(font
					(size 1.27 1.27)
				)
				(hide yes)
			)
		)
		(property "Author" "Antmicro"
			(at 171.45 156.21 0)
			(effects
				(font
					(size 1.27 1.27)
					(thickness 0.15)
				)
				(justify left bottom)
				(hide yes)
			)
		)
		(property "License" "Apache-2.0"
			(at 171.45 158.75 0)
			(effects
				(font
					(size 1.27 1.27)
					(thickness 0.15)
				)
				(justify left bottom)
				(hide yes)
			)
		)
		(pin "1"
		)
		(instances
			(project "thunderbolt-to-10gbe-adapter"
				(path ""
					(reference "#PWR0102")
					(unit 1)
				)
			)
		)
	)
	(symbol
		(lib_id "antmicropower:GND")
		(at 259.08 113.03 0)
		(unit 1)
		(exclude_from_sim no)
		(in_bom yes)
		(on_board yes)
		(dnp no)
		(property "Reference" "#PWR0133"
			(at 259.08 119.38 0)
			(effects
				(font
					(size 1.27 1.27)
				)
				(hide yes)
			)
		)
		(property "Value" "GND"
			(at 259.08 116.84 0)
			(effects
				(font
					(size 1.27 1.27)
				)
			)
		)
		(property "Footprint" ""
			(at 259.08 113.03 0)
			(effects
				(font
					(size 1.27 1.27)
				)
				(hide yes)
			)
		)
		(property "Datasheet" ""
			(at 259.08 113.03 0)
			(effects
				(font
					(size 1.27 1.27)
				)
				(hide yes)
			)
		)
		(property "Description" ""
			(at 259.08 113.03 0)
			(effects
				(font
					(size 1.27 1.27)
				)
				(hide yes)
			)
		)
		(property "Author" "Antmicro"
			(at 267.97 120.65 0)
			(effects
				(font
					(size 1.27 1.27)
					(thickness 0.15)
				)
				(justify left bottom)
				(hide yes)
			)
		)
		(property "License" "Apache-2.0"
			(at 267.97 123.19 0)
			(effects
				(font
					(size 1.27 1.27)
					(thickness 0.15)
				)
				(justify left bottom)
				(hide yes)
			)
		)
		(pin "1"
		)
		(instances
			(project "thunderbolt-to-10gbe-adapter"
				(path ""
					(reference "#PWR0133")
					(unit 1)
				)
			)
		)
	)
	(symbol
		(lib_id "antmicropower:GND")
		(at 271.78 80.01 0)
		(unit 1)
		(exclude_from_sim no)
		(in_bom yes)
		(on_board yes)
		(dnp no)
		(property "Reference" "#PWR0140"
			(at 271.78 86.36 0)
			(effects
				(font
					(size 1.27 1.27)
				)
				(hide yes)
			)
		)
		(property "Value" "GND"
			(at 271.78 83.82 0)
			(effects
				(font
					(size 1.27 1.27)
				)
			)
		)
		(property "Footprint" ""
			(at 271.78 80.01 0)
			(effects
				(font
					(size 1.27 1.27)
				)
				(hide yes)
			)
		)
		(property "Datasheet" ""
			(at 271.78 80.01 0)
			(effects
				(font
					(size 1.27 1.27)
				)
				(hide yes)
			)
		)
		(property "Description" ""
			(at 271.78 80.01 0)
			(effects
				(font
					(size 1.27 1.27)
				)
				(hide yes)
			)
		)
		(property "Author" "Antmicro"
			(at 280.67 87.63 0)
			(effects
				(font
					(size 1.27 1.27)
					(thickness 0.15)
				)
				(justify left bottom)
				(hide yes)
			)
		)
		(property "License" "Apache-2.0"
			(at 280.67 90.17 0)
			(effects
				(font
					(size 1.27 1.27)
					(thickness 0.15)
				)
				(justify left bottom)
				(hide yes)
			)
		)
		(pin "1"
		)
		(instances
			(project "thunderbolt-to-10gbe-adapter"
				(path ""
					(reference "#PWR0140")
					(unit 1)
				)
			)
		)
	)
	(symbol
		(lib_id "antmicropower:GND")
		(at 246.38 148.59 0)
		(unit 1)
		(exclude_from_sim no)
		(in_bom yes)
		(on_board yes)
		(dnp no)
		(property "Reference" "#PWR0123"
			(at 246.38 154.94 0)
			(effects
				(font
					(size 1.27 1.27)
				)
				(hide yes)
			)
		)
		(property "Value" "GND"
			(at 246.38 152.4 0)
			(effects
				(font
					(size 1.27 1.27)
				)
			)
		)
		(property "Footprint" ""
			(at 246.38 148.59 0)
			(effects
				(font
					(size 1.27 1.27)
				)
				(hide yes)
			)
		)
		(property "Datasheet" ""
			(at 246.38 148.59 0)
			(effects
				(font
					(size 1.27 1.27)
				)
				(hide yes)
			)
		)
		(property "Description" ""
			(at 246.38 148.59 0)
			(effects
				(font
					(size 1.27 1.27)
				)
				(hide yes)
			)
		)
		(property "Author" "Antmicro"
			(at 255.27 156.21 0)
			(effects
				(font
					(size 1.27 1.27)
					(thickness 0.15)
				)
				(justify left bottom)
				(hide yes)
			)
		)
		(property "License" "Apache-2.0"
			(at 255.27 158.75 0)
			(effects
				(font
					(size 1.27 1.27)
					(thickness 0.15)
				)
				(justify left bottom)
				(hide yes)
			)
		)
		(pin "1"
		)
		(instances
			(project "thunderbolt-to-10gbe-adapter"
				(path ""
					(reference "#PWR0123")
					(unit 1)
				)
			)
		)
	)
	(symbol
		(lib_id "antmicropower:+3V3")
		(at 254 195.58 0)
		(unit 1)
		(exclude_from_sim no)
		(in_bom yes)
		(on_board yes)
		(dnp no)
		(property "Reference" "#PWR0130"
			(at 269.24 195.58 0)
			(effects
				(font
					(size 1.27 1.27)
					(thickness 0.15)
				)
				(justify left bottom)
				(hide yes)
			)
		)
		(property "Value" "+3V3_TB"
			(at 254 191.77 0)
			(effects
				(font
					(size 1.27 1.27)
					(thickness 0.15)
				)
			)
		)
		(property "Footprint" ""
			(at 269.24 203.2 0)
			(effects
				(font
					(size 1.27 1.27)
					(thickness 0.15)
				)
				(justify left bottom)
				(hide yes)
			)
		)
		(property "Datasheet" ""
			(at 269.24 205.74 0)
			(effects
				(font
					(size 1.27 1.27)
					(thickness 0.15)
				)
				(justify left bottom)
				(hide yes)
			)
		)
		(property "Description" ""
			(at 269.24 208.28 0)
			(effects
				(font
					(size 1.27 1.27)
				)
				(justify left bottom)
				(hide yes)
			)
		)
		(property "Author" "Antmicro"
			(at 269.24 198.12 0)
			(effects
				(font
					(size 1.27 1.27)
					(thickness 0.15)
				)
				(justify left bottom)
				(hide yes)
			)
		)
		(property "License" "Apache-2.0"
			(at 269.24 200.66 0)
			(effects
				(font
					(size 1.27 1.27)
					(thickness 0.15)
				)
				(justify left bottom)
				(hide yes)
			)
		)
		(pin "1"
		)
		(instances
			(project "thunderbolt-to-10gbe-adapter"
				(path ""
					(reference "#PWR0130")
					(unit 1)
				)
			)
		)
	)
	(symbol
		(lib_id "antmicropower:GND")
		(at 152.4 114.3 0)
		(unit 1)
		(exclude_from_sim no)
		(in_bom yes)
		(on_board yes)
		(dnp no)
		(property "Reference" "#PWR089"
			(at 152.4 120.65 0)
			(effects
				(font
					(size 1.27 1.27)
				)
				(hide yes)
			)
		)
		(property "Value" "GND"
			(at 152.4 118.11 0)
			(effects
				(font
					(size 1.27 1.27)
				)
			)
		)
		(property "Footprint" ""
			(at 152.4 114.3 0)
			(effects
				(font
					(size 1.27 1.27)
				)
				(hide yes)
			)
		)
		(property "Datasheet" ""
			(at 152.4 114.3 0)
			(effects
				(font
					(size 1.27 1.27)
				)
				(hide yes)
			)
		)
		(property "Description" ""
			(at 152.4 114.3 0)
			(effects
				(font
					(size 1.27 1.27)
				)
				(hide yes)
			)
		)
		(property "Author" "Antmicro"
			(at 161.29 121.92 0)
			(effects
				(font
					(size 1.27 1.27)
					(thickness 0.15)
				)
				(justify left bottom)
				(hide yes)
			)
		)
		(property "License" "Apache-2.0"
			(at 161.29 124.46 0)
			(effects
				(font
					(size 1.27 1.27)
					(thickness 0.15)
				)
				(justify left bottom)
				(hide yes)
			)
		)
		(pin "1"
		)
		(instances
			(project "thunderbolt-to-10gbe-adapter"
				(path ""
					(reference "#PWR089")
					(unit 1)
				)
			)
		)
	)
	(symbol
		(lib_id "antmicropower:GND")
		(at 227.33 129.54 0)
		(unit 1)
		(exclude_from_sim no)
		(in_bom yes)
		(on_board yes)
		(dnp no)
		(property "Reference" "#PWR0109"
			(at 227.33 135.89 0)
			(effects
				(font
					(size 1.27 1.27)
				)
				(hide yes)
			)
		)
		(property "Value" "GND"
			(at 227.33 133.35 0)
			(effects
				(font
					(size 1.27 1.27)
				)
			)
		)
		(property "Footprint" ""
			(at 227.33 129.54 0)
			(effects
				(font
					(size 1.27 1.27)
				)
				(hide yes)
			)
		)
		(property "Datasheet" ""
			(at 227.33 129.54 0)
			(effects
				(font
					(size 1.27 1.27)
				)
				(hide yes)
			)
		)
		(property "Description" ""
			(at 227.33 129.54 0)
			(effects
				(font
					(size 1.27 1.27)
				)
				(hide yes)
			)
		)
		(property "Author" "Antmicro"
			(at 236.22 137.16 0)
			(effects
				(font
					(size 1.27 1.27)
					(thickness 0.15)
				)
				(justify left bottom)
				(hide yes)
			)
		)
		(property "License" "Apache-2.0"
			(at 236.22 139.7 0)
			(effects
				(font
					(size 1.27 1.27)
					(thickness 0.15)
				)
				(justify left bottom)
				(hide yes)
			)
		)
		(pin "1"
		)
		(instances
			(project "thunderbolt-to-10gbe-adapter"
				(path ""
					(reference "#PWR0109")
					(unit 1)
				)
			)
		)
	)
	(symbol
		(lib_id "antmicroResistors0402:R_1k_0402")
		(at 262.89 167.64 90)
		(unit 1)
		(exclude_from_sim no)
		(in_bom yes)
		(on_board yes)
		(dnp no)
		(fields_autoplaced yes)
		(property "Reference" "R76"
			(at 265.43 163.83 90)
			(effects
				(font
					(size 1.27 1.27)
					(thickness 0.15)
				)
				(justify right)
			)
		)
		(property "Value" "R_1k_0402"
			(at 275.59 147.32 0)
			(effects
				(font
					(size 1.27 1.27)
					(thickness 0.15)
				)
				(justify left bottom)
				(hide yes)
			)
		)
		(property "Footprint" "antmicro-footprints:R_0402_1005Metric"
			(at 278.13 147.32 0)
			(effects
				(font
					(size 1.27 1.27)
					(thickness 0.15)
				)
				(justify left bottom)
				(hide yes)
			)
		)
		(property "Datasheet" "https://www.bourns.com/docs/product-datasheets/cr.pdf"
			(at 280.67 147.32 0)
			(effects
				(font
					(size 1.27 1.27)
					(thickness 0.15)
				)
				(justify left bottom)
				(hide yes)
			)
		)
		(property "Description" "SMD Chip Resistor, 1 kohm, ± 1%, 63 mW, 0402 [1005 Metric], Thick Film, General Purpose"
			(at 262.89 167.64 0)
			(effects
				(font
					(size 1.27 1.27)
				)
				(hide yes)
			)
		)
		(property "MPN" "CR0402-FX-1001GLF"
			(at 283.21 147.32 0)
			(effects
				(font
					(size 1.27 1.27)
					(thickness 0.15)
				)
				(justify left bottom)
				(hide yes)
			)
		)
		(property "Manufacturer" "Bourns"
			(at 285.75 147.32 0)
			(effects
				(font
					(size 1.27 1.27)
					(thickness 0.15)
				)
				(justify left bottom)
				(hide yes)
			)
		)
		(property "License" "Apache-2.0"
			(at 288.29 147.32 0)
			(effects
				(font
					(size 1.27 1.27)
					(thickness 0.15)
				)
				(justify left bottom)
				(hide yes)
			)
		)
		(property "Author" "Antmicro"
			(at 290.83 147.32 0)
			(effects
				(font
					(size 1.27 1.27)
					(thickness 0.15)
				)
				(justify left bottom)
				(hide yes)
			)
		)
		(property "Val" "1k"
			(at 265.43 166.37 90)
			(effects
				(font
					(size 1.27 1.27)
					(thickness 0.15)
				)
				(justify right)
			)
		)
		(property "Tolerance" "1%"
			(at 273.05 147.32 0)
			(effects
				(font
					(size 1.27 1.27)
				)
				(justify left bottom)
				(hide yes)
			)
		)
		(pin "1"
		)
		(pin "2"
		)
		(instances
			(project "thunderbolt-to-10gbe-adapter"
				(path ""
					(reference "R76")
					(unit 1)
				)
			)
		)
	)
	(symbol
		(lib_id "antmicropower:PWR_FLAG")
		(at 226.06 157.48 180)
		(unit 1)
		(exclude_from_sim no)
		(in_bom yes)
		(on_board yes)
		(dnp no)
		(fields_autoplaced yes)
		(property "Reference" "#FLG015"
			(at 226.06 159.385 0)
			(effects
				(font
					(size 1.27 1.27)
				)
				(hide yes)
			)
		)
		(property "Value" "PWR_FLAG"
			(at 226.06 162.56 0)
			(effects
				(font
					(size 1.27 1.27)
				)
			)
		)
		(property "Footprint" ""
			(at 226.06 157.48 0)
			(effects
				(font
					(size 1.27 1.27)
				)
				(hide yes)
			)
		)
		(property "Datasheet" ""
			(at 226.06 157.48 0)
			(effects
				(font
					(size 1.27 1.27)
				)
				(hide yes)
			)
		)
		(property "Description" ""
			(at 226.06 154.94 0)
			(effects
				(font
					(size 1.27 1.27)
				)
				(justify left bottom)
				(hide yes)
			)
		)
		(pin "1"
		)
		(instances
			(project "thunderbolt-to-10gbe-adapter"
				(path ""
					(reference "#FLG015")
					(unit 1)
				)
			)
		)
	)
	(symbol
		(lib_id "antmicroCapacitors0402:C_1u_0402")
		(at 162.56 147.32 90)
		(unit 1)
		(exclude_from_sim no)
		(in_bom yes)
		(on_board yes)
		(dnp no)
		(property "Reference" "C72"
			(at 163.195 142.875 90)
			(effects
				(font
					(size 1.27 1.27)
					(thickness 0.15)
				)
				(justify right)
			)
		)
		(property "Value" "C_1u_0402"
			(at 172.72 127 0)
			(effects
				(font
					(size 1.27 1.27)
					(thickness 0.15)
				)
				(justify left bottom)
				(hide yes)
			)
		)
		(property "Footprint" "antmicro-footprints:C_0402_1005Metric"
			(at 175.26 127 0)
			(effects
				(font
					(size 1.27 1.27)
					(thickness 0.15)
				)
				(justify left bottom)
				(hide yes)
			)
		)
		(property "Datasheet" "https://product.tdk.com/en/search/capacitor/ceramic/mlcc/info?part_no=C1005X6S1A105K050BC"
			(at 177.8 127 0)
			(effects
				(font
					(size 1.27 1.27)
					(thickness 0.15)
				)
				(justify left bottom)
				(hide yes)
			)
		)
		(property "Description" "SMD Multilayer Ceramic Capacitor, 1 µF, 10 V, 0402 [1005 Metric], ± 10%, X6S, C"
			(at 162.56 147.32 0)
			(effects
				(font
					(size 1.27 1.27)
				)
				(hide yes)
			)
		)
		(property "MPN" "C1005X6S1A105K050BC"
			(at 180.34 127 0)
			(effects
				(font
					(size 1.27 1.27)
					(thickness 0.15)
				)
				(justify left bottom)
				(hide yes)
			)
		)
		(property "Manufacturer" "TDK"
			(at 182.88 127 0)
			(effects
				(font
					(size 1.27 1.27)
					(thickness 0.15)
				)
				(justify left bottom)
				(hide yes)
			)
		)
		(property "License" "Apache-2.0"
			(at 185.42 127 0)
			(effects
				(font
					(size 1.27 1.27)
					(thickness 0.15)
				)
				(justify left bottom)
				(hide yes)
			)
		)
		(property "Val" "1u"
			(at 163.195 146.685 90)
			(effects
				(font
					(size 1.27 1.27)
					(thickness 0.15)
				)
				(justify right)
			)
		)
		(property "Voltage" ""
			(at 190.5 127 0)
			(effects
				(font
					(size 1.27 1.27)
				)
				(justify left bottom)
				(hide yes)
			)
		)
		(property "Dielectric" ""
			(at 193.04 127 0)
			(effects
				(font
					(size 1.27 1.27)
				)
				(justify left bottom)
				(hide yes)
			)
		)
		(property "Author" "Antmicro"
			(at 187.96 127 0)
			(effects
				(font
					(size 1.27 1.27)
					(thickness 0.15)
				)
				(justify left bottom)
				(hide yes)
			)
		)
		(pin "1"
		)
		(pin "2"
		)
		(instances
			(project "thunderbolt-to-10gbe-adapter"
				(path ""
					(reference "C72")
					(unit 1)
				)
			)
		)
	)
	(symbol
		(lib_id "antmicropower:GND")
		(at 224.79 143.51 0)
		(unit 1)
		(exclude_from_sim no)
		(in_bom yes)
		(on_board yes)
		(dnp no)
		(property "Reference" "#PWR0104"
			(at 224.79 149.86 0)
			(effects
				(font
					(size 1.27 1.27)
				)
				(hide yes)
			)
		)
		(property "Value" "GND"
			(at 224.79 147.32 0)
			(effects
				(font
					(size 1.27 1.27)
				)
			)
		)
		(property "Footprint" ""
			(at 224.79 143.51 0)
			(effects
				(font
					(size 1.27 1.27)
				)
				(hide yes)
			)
		)
		(property "Datasheet" ""
			(at 224.79 143.51 0)
			(effects
				(font
					(size 1.27 1.27)
				)
				(hide yes)
			)
		)
		(property "Description" ""
			(at 224.79 143.51 0)
			(effects
				(font
					(size 1.27 1.27)
				)
				(hide yes)
			)
		)
		(property "Author" "Antmicro"
			(at 233.68 151.13 0)
			(effects
				(font
					(size 1.27 1.27)
					(thickness 0.15)
				)
				(justify left bottom)
				(hide yes)
			)
		)
		(property "License" "Apache-2.0"
			(at 233.68 153.67 0)
			(effects
				(font
					(size 1.27 1.27)
					(thickness 0.15)
				)
				(justify left bottom)
				(hide yes)
			)
		)
		(pin "1"
		)
		(instances
			(project "thunderbolt-to-10gbe-adapter"
				(path ""
					(reference "#PWR0104")
					(unit 1)
				)
			)
		)
	)
	(symbol
		(lib_id "antmicroCapacitors0402:C_1u_0402")
		(at 233.68 165.1 90)
		(unit 1)
		(exclude_from_sim no)
		(in_bom yes)
		(on_board yes)
		(dnp no)
		(fields_autoplaced yes)
		(property "Reference" "C81"
			(at 234.315 160.655 90)
			(effects
				(font
					(size 1.27 1.27)
					(thickness 0.15)
				)
				(justify right)
			)
		)
		(property "Value" "C_1u_0402"
			(at 243.84 144.78 0)
			(effects
				(font
					(size 1.27 1.27)
					(thickness 0.15)
				)
				(justify left bottom)
				(hide yes)
			)
		)
		(property "Footprint" "antmicro-footprints:C_0402_1005Metric"
			(at 246.38 144.78 0)
			(effects
				(font
					(size 1.27 1.27)
					(thickness 0.15)
				)
				(justify left bottom)
				(hide yes)
			)
		)
		(property "Datasheet" "https://product.tdk.com/en/search/capacitor/ceramic/mlcc/info?part_no=C1005X6S1A105K050BC"
			(at 248.92 144.78 0)
			(effects
				(font
					(size 1.27 1.27)
					(thickness 0.15)
				)
				(justify left bottom)
				(hide yes)
			)
		)
		(property "Description" "SMD Multilayer Ceramic Capacitor, 1 µF, 10 V, 0402 [1005 Metric], ± 10%, X6S, C"
			(at 233.68 165.1 0)
			(effects
				(font
					(size 1.27 1.27)
				)
				(hide yes)
			)
		)
		(property "MPN" "C1005X6S1A105K050BC"
			(at 251.46 144.78 0)
			(effects
				(font
					(size 1.27 1.27)
					(thickness 0.15)
				)
				(justify left bottom)
				(hide yes)
			)
		)
		(property "Manufacturer" "TDK"
			(at 254 144.78 0)
			(effects
				(font
					(size 1.27 1.27)
					(thickness 0.15)
				)
				(justify left bottom)
				(hide yes)
			)
		)
		(property "License" "Apache-2.0"
			(at 256.54 144.78 0)
			(effects
				(font
					(size 1.27 1.27)
					(thickness 0.15)
				)
				(justify left bottom)
				(hide yes)
			)
		)
		(property "Val" "1u"
			(at 234.315 164.465 90)
			(effects
				(font
					(size 1.27 1.27)
					(thickness 0.15)
				)
				(justify right)
			)
		)
		(property "Voltage" ""
			(at 261.62 144.78 0)
			(effects
				(font
					(size 1.27 1.27)
				)
				(justify left bottom)
				(hide yes)
			)
		)
		(property "Dielectric" ""
			(at 264.16 144.78 0)
			(effects
				(font
					(size 1.27 1.27)
				)
				(justify left bottom)
				(hide yes)
			)
		)
		(property "Author" "Antmicro"
			(at 259.08 144.78 0)
			(effects
				(font
					(size 1.27 1.27)
					(thickness 0.15)
				)
				(justify left bottom)
				(hide yes)
			)
		)
		(pin "1"
		)
		(pin "2"
		)
		(instances
			(project "thunderbolt-to-10gbe-adapter"
				(path ""
					(reference "C81")
					(unit 1)
				)
			)
		)
	)
	(symbol
		(lib_id "antmicroFixedInductors:L_680n_7.6A_IHLP1616BZ")
		(at 224.79 138.43 0)
		(unit 1)
		(exclude_from_sim no)
		(in_bom yes)
		(on_board yes)
		(dnp no)
		(property "Reference" "L2"
			(at 223.52 137.16 0)
			(effects
				(font
					(size 1.27 1.27)
					(thickness 0.15)
				)
			)
		)
		(property "Value" "L_680n_7.6A_IHLP1616BZ"
			(at 238.76 140.97 0)
			(effects
				(font
					(size 1.27 1.27)
					(thickness 0.15)
				)
				(justify left bottom)
				(hide yes)
			)
		)
		(property "Footprint" "antmicro-footprints:L_Vishay-IHLP1616BZ"
			(at 238.76 146.05 0)
			(effects
				(font
					(size 1.27 1.27)
					(thickness 0.15)
				)
				(justify left bottom)
				(hide yes)
			)
		)
		(property "Datasheet" "https://www.mouser.com/datasheet/2/427/ihlp1616bz5a-1763007.pdf"
			(at 238.76 148.59 0)
			(effects
				(font
					(size 1.27 1.27)
					(thickness 0.15)
				)
				(justify left bottom)
				(hide yes)
			)
		)
		(property "Description" "Power Inductor (SMT), 680 nH, 7.6 A, Shielded, 6.8 A, IHLP-1616BZ-5A"
			(at 224.79 138.43 0)
			(effects
				(font
					(size 1.27 1.27)
				)
				(hide yes)
			)
		)
		(property "Val" "680n/7.6A"
			(at 234.95 137.16 0)
			(effects
				(font
					(size 1.27 1.27)
					(thickness 0.15)
				)
			)
		)
		(property "Manufacturer" "Vishay"
			(at 238.76 151.13 0)
			(effects
				(font
					(size 1.27 1.27)
					(thickness 0.15)
				)
				(justify left bottom)
				(hide yes)
			)
		)
		(property "MPN" "IHLP1616BZERR68M5A"
			(at 238.76 153.67 0)
			(effects
				(font
					(size 1.27 1.27)
					(thickness 0.15)
				)
				(justify left bottom)
				(hide yes)
			)
		)
		(property "ISat" "6.8 A"
			(at 238.76 154.94 0)
			(effects
				(font
					(size 1.27 1.27)
				)
				(justify left)
				(hide yes)
			)
		)
		(property "IMax" "7.6 A"
			(at 238.76 158.75 0)
			(effects
				(font
					(size 1.27 1.27)
					(thickness 0.15)
				)
				(justify left bottom)
				(hide yes)
			)
		)
		(property "Size" "4.06x4.06"
			(at 238.76 161.29 0)
			(effects
				(font
					(size 1.27 1.27)
					(thickness 0.15)
				)
				(justify left bottom)
				(hide yes)
			)
		)
		(property "Author" "Antmicro"
			(at 238.76 163.83 0)
			(effects
				(font
					(size 1.27 1.27)
					(thickness 0.15)
				)
				(justify left bottom)
				(hide yes)
			)
		)
		(property "License" "Apache-2.0"
			(at 238.76 166.37 0)
			(effects
				(font
					(size 1.27 1.27)
					(thickness 0.15)
				)
				(justify left bottom)
				(hide yes)
			)
		)
		(pin "1"
		)
		(pin "2"
		)
		(instances
			(project "thunderbolt-to-10gbe-adapter"
				(path ""
					(reference "L2")
					(unit 1)
				)
			)
		)
	)
	(symbol
		(lib_id "antmicroCapacitors0402:C_1u_0402")
		(at 240.03 165.1 90)
		(unit 1)
		(exclude_from_sim no)
		(in_bom yes)
		(on_board yes)
		(dnp no)
		(fields_autoplaced yes)
		(property "Reference" "C85"
			(at 240.665 160.655 90)
			(effects
				(font
					(size 1.27 1.27)
					(thickness 0.15)
				)
				(justify right)
			)
		)
		(property "Value" "C_1u_0402"
			(at 250.19 144.78 0)
			(effects
				(font
					(size 1.27 1.27)
					(thickness 0.15)
				)
				(justify left bottom)
				(hide yes)
			)
		)
		(property "Footprint" "antmicro-footprints:C_0402_1005Metric"
			(at 252.73 144.78 0)
			(effects
				(font
					(size 1.27 1.27)
					(thickness 0.15)
				)
				(justify left bottom)
				(hide yes)
			)
		)
		(property "Datasheet" "https://product.tdk.com/en/search/capacitor/ceramic/mlcc/info?part_no=C1005X6S1A105K050BC"
			(at 255.27 144.78 0)
			(effects
				(font
					(size 1.27 1.27)
					(thickness 0.15)
				)
				(justify left bottom)
				(hide yes)
			)
		)
		(property "Description" "SMD Multilayer Ceramic Capacitor, 1 µF, 10 V, 0402 [1005 Metric], ± 10%, X6S, C"
			(at 240.03 165.1 0)
			(effects
				(font
					(size 1.27 1.27)
				)
				(hide yes)
			)
		)
		(property "MPN" "C1005X6S1A105K050BC"
			(at 257.81 144.78 0)
			(effects
				(font
					(size 1.27 1.27)
					(thickness 0.15)
				)
				(justify left bottom)
				(hide yes)
			)
		)
		(property "Manufacturer" "TDK"
			(at 260.35 144.78 0)
			(effects
				(font
					(size 1.27 1.27)
					(thickness 0.15)
				)
				(justify left bottom)
				(hide yes)
			)
		)
		(property "License" "Apache-2.0"
			(at 262.89 144.78 0)
			(effects
				(font
					(size 1.27 1.27)
					(thickness 0.15)
				)
				(justify left bottom)
				(hide yes)
			)
		)
		(property "Val" "1u"
			(at 240.665 164.465 90)
			(effects
				(font
					(size 1.27 1.27)
					(thickness 0.15)
				)
				(justify right)
			)
		)
		(property "Voltage" ""
			(at 267.97 144.78 0)
			(effects
				(font
					(size 1.27 1.27)
				)
				(justify left bottom)
				(hide yes)
			)
		)
		(property "Dielectric" ""
			(at 270.51 144.78 0)
			(effects
				(font
					(size 1.27 1.27)
				)
				(justify left bottom)
				(hide yes)
			)
		)
		(property "Author" "Antmicro"
			(at 265.43 144.78 0)
			(effects
				(font
					(size 1.27 1.27)
					(thickness 0.15)
				)
				(justify left bottom)
				(hide yes)
			)
		)
		(pin "1"
		)
		(pin "2"
		)
		(instances
			(project "thunderbolt-to-10gbe-adapter"
				(path ""
					(reference "C85")
					(unit 1)
				)
			)
		)
	)
	(symbol
		(lib_id "antmicroCapacitors0402:C_1u_0402")
		(at 252.73 110.49 90)
		(unit 1)
		(exclude_from_sim no)
		(in_bom yes)
		(on_board yes)
		(dnp no)
		(fields_autoplaced yes)
		(property "Reference" "C92"
			(at 253.365 106.045 90)
			(effects
				(font
					(size 1.27 1.27)
					(thickness 0.15)
				)
				(justify right)
			)
		)
		(property "Value" "C_1u_0402"
			(at 262.89 90.17 0)
			(effects
				(font
					(size 1.27 1.27)
					(thickness 0.15)
				)
				(justify left bottom)
				(hide yes)
			)
		)
		(property "Footprint" "antmicro-footprints:C_0402_1005Metric"
			(at 265.43 90.17 0)
			(effects
				(font
					(size 1.27 1.27)
					(thickness 0.15)
				)
				(justify left bottom)
				(hide yes)
			)
		)
		(property "Datasheet" "https://product.tdk.com/en/search/capacitor/ceramic/mlcc/info?part_no=C1005X6S1A105K050BC"
			(at 267.97 90.17 0)
			(effects
				(font
					(size 1.27 1.27)
					(thickness 0.15)
				)
				(justify left bottom)
				(hide yes)
			)
		)
		(property "Description" "SMD Multilayer Ceramic Capacitor, 1 µF, 10 V, 0402 [1005 Metric], ± 10%, X6S, C"
			(at 252.73 110.49 0)
			(effects
				(font
					(size 1.27 1.27)
				)
				(hide yes)
			)
		)
		(property "MPN" "C1005X6S1A105K050BC"
			(at 270.51 90.17 0)
			(effects
				(font
					(size 1.27 1.27)
					(thickness 0.15)
				)
				(justify left bottom)
				(hide yes)
			)
		)
		(property "Manufacturer" "TDK"
			(at 273.05 90.17 0)
			(effects
				(font
					(size 1.27 1.27)
					(thickness 0.15)
				)
				(justify left bottom)
				(hide yes)
			)
		)
		(property "License" "Apache-2.0"
			(at 275.59 90.17 0)
			(effects
				(font
					(size 1.27 1.27)
					(thickness 0.15)
				)
				(justify left bottom)
				(hide yes)
			)
		)
		(property "Val" "1u"
			(at 253.365 109.855 90)
			(effects
				(font
					(size 1.27 1.27)
					(thickness 0.15)
				)
				(justify right)
			)
		)
		(property "Voltage" ""
			(at 280.67 90.17 0)
			(effects
				(font
					(size 1.27 1.27)
				)
				(justify left bottom)
				(hide yes)
			)
		)
		(property "Dielectric" ""
			(at 283.21 90.17 0)
			(effects
				(font
					(size 1.27 1.27)
				)
				(justify left bottom)
				(hide yes)
			)
		)
		(property "Author" "Antmicro"
			(at 278.13 90.17 0)
			(effects
				(font
					(size 1.27 1.27)
					(thickness 0.15)
				)
				(justify left bottom)
				(hide yes)
			)
		)
		(pin "1"
		)
		(pin "2"
		)
		(instances
			(project "thunderbolt-to-10gbe-adapter"
				(path ""
					(reference "C92")
					(unit 1)
				)
			)
		)
	)
	(symbol
		(lib_id "antmicropower:+3V3")
		(at 279.4 68.58 0)
		(unit 1)
		(exclude_from_sim no)
		(in_bom yes)
		(on_board yes)
		(dnp no)
		(property "Reference" "#PWR0142"
			(at 294.64 68.58 0)
			(effects
				(font
					(size 1.27 1.27)
					(thickness 0.15)
				)
				(justify left bottom)
				(hide yes)
			)
		)
		(property "Value" "+3V3_TB"
			(at 279.4 64.77 0)
			(effects
				(font
					(size 1.27 1.27)
					(thickness 0.15)
				)
			)
		)
		(property "Footprint" ""
			(at 294.64 76.2 0)
			(effects
				(font
					(size 1.27 1.27)
					(thickness 0.15)
				)
				(justify left bottom)
				(hide yes)
			)
		)
		(property "Datasheet" ""
			(at 294.64 78.74 0)
			(effects
				(font
					(size 1.27 1.27)
					(thickness 0.15)
				)
				(justify left bottom)
				(hide yes)
			)
		)
		(property "Description" ""
			(at 294.64 81.28 0)
			(effects
				(font
					(size 1.27 1.27)
				)
				(justify left bottom)
				(hide yes)
			)
		)
		(property "Author" "Antmicro"
			(at 294.64 71.12 0)
			(effects
				(font
					(size 1.27 1.27)
					(thickness 0.15)
				)
				(justify left bottom)
				(hide yes)
			)
		)
		(property "License" "Apache-2.0"
			(at 294.64 73.66 0)
			(effects
				(font
					(size 1.27 1.27)
					(thickness 0.15)
				)
				(justify left bottom)
				(hide yes)
			)
		)
		(pin "1"
		)
		(instances
			(project "thunderbolt-to-10gbe-adapter"
				(path ""
					(reference "#PWR0142")
					(unit 1)
				)
			)
		)
	)
	(symbol
		(lib_id "antmicropower:PWR_FLAG")
		(at 152.4 156.21 90)
		(unit 1)
		(exclude_from_sim no)
		(in_bom yes)
		(on_board yes)
		(dnp no)
		(fields_autoplaced yes)
		(property "Reference" "#FLG012"
			(at 150.495 156.21 0)
			(effects
				(font
					(size 1.27 1.27)
				)
				(hide yes)
			)
		)
		(property "Value" "PWR_FLAG"
			(at 148.59 156.2099 90)
			(effects
				(font
					(size 1.27 1.27)
				)
				(justify left)
			)
		)
		(property "Footprint" ""
			(at 152.4 156.21 0)
			(effects
				(font
					(size 1.27 1.27)
				)
				(hide yes)
			)
		)
		(property "Datasheet" ""
			(at 152.4 156.21 0)
			(effects
				(font
					(size 1.27 1.27)
				)
				(hide yes)
			)
		)
		(property "Description" ""
			(at 154.94 156.21 0)
			(effects
				(font
					(size 1.27 1.27)
				)
				(justify left bottom)
				(hide yes)
			)
		)
		(pin "1"
		)
		(instances
			(project "thunderbolt-to-10gbe-adapter"
				(path ""
					(reference "#FLG012")
					(unit 1)
				)
			)
		)
	)
	(symbol
		(lib_id "antmicroCapacitors0402:C_1u_0402")
		(at 157.48 111.76 90)
		(unit 1)
		(exclude_from_sim no)
		(in_bom yes)
		(on_board yes)
		(dnp no)
		(property "Reference" "C65"
			(at 158.115 107.315 90)
			(effects
				(font
					(size 1.27 1.27)
					(thickness 0.15)
				)
				(justify right)
			)
		)
		(property "Value" "C_1u_0402"
			(at 167.64 91.44 0)
			(effects
				(font
					(size 1.27 1.27)
					(thickness 0.15)
				)
				(justify left bottom)
				(hide yes)
			)
		)
		(property "Footprint" "antmicro-footprints:C_0402_1005Metric"
			(at 170.18 91.44 0)
			(effects
				(font
					(size 1.27 1.27)
					(thickness 0.15)
				)
				(justify left bottom)
				(hide yes)
			)
		)
		(property "Datasheet" "https://product.tdk.com/en/search/capacitor/ceramic/mlcc/info?part_no=C1005X6S1A105K050BC"
			(at 172.72 91.44 0)
			(effects
				(font
					(size 1.27 1.27)
					(thickness 0.15)
				)
				(justify left bottom)
				(hide yes)
			)
		)
		(property "Description" "SMD Multilayer Ceramic Capacitor, 1 µF, 10 V, 0402 [1005 Metric], ± 10%, X6S, C"
			(at 157.48 111.76 0)
			(effects
				(font
					(size 1.27 1.27)
				)
				(hide yes)
			)
		)
		(property "MPN" "C1005X6S1A105K050BC"
			(at 175.26 91.44 0)
			(effects
				(font
					(size 1.27 1.27)
					(thickness 0.15)
				)
				(justify left bottom)
				(hide yes)
			)
		)
		(property "Manufacturer" "TDK"
			(at 177.8 91.44 0)
			(effects
				(font
					(size 1.27 1.27)
					(thickness 0.15)
				)
				(justify left bottom)
				(hide yes)
			)
		)
		(property "License" "Apache-2.0"
			(at 180.34 91.44 0)
			(effects
				(font
					(size 1.27 1.27)
					(thickness 0.15)
				)
				(justify left bottom)
				(hide yes)
			)
		)
		(property "Val" "1u"
			(at 158.115 111.125 90)
			(effects
				(font
					(size 1.27 1.27)
					(thickness 0.15)
				)
				(justify right)
			)
		)
		(property "Voltage" ""
			(at 185.42 91.44 0)
			(effects
				(font
					(size 1.27 1.27)
				)
				(justify left bottom)
				(hide yes)
			)
		)
		(property "Dielectric" ""
			(at 187.96 91.44 0)
			(effects
				(font
					(size 1.27 1.27)
				)
				(justify left bottom)
				(hide yes)
			)
		)
		(property "Author" "Antmicro"
			(at 182.88 91.44 0)
			(effects
				(font
					(size 1.27 1.27)
					(thickness 0.15)
				)
				(justify left bottom)
				(hide yes)
			)
		)
		(pin "1"
		)
		(pin "2"
		)
		(instances
			(project "thunderbolt-to-10gbe-adapter"
				(path ""
					(reference "C65")
					(unit 1)
				)
			)
		)
	)
	(symbol
		(lib_id "antmicropower:GND")
		(at 153.67 168.91 0)
		(unit 1)
		(exclude_from_sim no)
		(in_bom yes)
		(on_board yes)
		(dnp no)
		(property "Reference" "#PWR091"
			(at 153.67 175.26 0)
			(effects
				(font
					(size 1.27 1.27)
				)
				(hide yes)
			)
		)
		(property "Value" "GND"
			(at 153.67 172.72 0)
			(effects
				(font
					(size 1.27 1.27)
				)
			)
		)
		(property "Footprint" ""
			(at 153.67 168.91 0)
			(effects
				(font
					(size 1.27 1.27)
				)
				(hide yes)
			)
		)
		(property "Datasheet" ""
			(at 153.67 168.91 0)
			(effects
				(font
					(size 1.27 1.27)
				)
				(hide yes)
			)
		)
		(property "Description" ""
			(at 153.67 168.91 0)
			(effects
				(font
					(size 1.27 1.27)
				)
				(hide yes)
			)
		)
		(property "Author" "Antmicro"
			(at 162.56 176.53 0)
			(effects
				(font
					(size 1.27 1.27)
					(thickness 0.15)
				)
				(justify left bottom)
				(hide yes)
			)
		)
		(property "License" "Apache-2.0"
			(at 162.56 179.07 0)
			(effects
				(font
					(size 1.27 1.27)
					(thickness 0.15)
				)
				(justify left bottom)
				(hide yes)
			)
		)
		(pin "1"
		)
		(instances
			(project "thunderbolt-to-10gbe-adapter"
				(path ""
					(reference "#PWR091")
					(unit 1)
				)
			)
		)
	)
	(symbol
		(lib_id "antmicroCapacitors0402:C_1u_0402")
		(at 227.33 128.27 90)
		(unit 1)
		(exclude_from_sim no)
		(in_bom yes)
		(on_board yes)
		(dnp no)
		(property "Reference" "C76"
			(at 227.965 123.825 90)
			(effects
				(font
					(size 1.27 1.27)
					(thickness 0.15)
				)
				(justify right)
			)
		)
		(property "Value" "C_1u_0402"
			(at 237.49 107.95 0)
			(effects
				(font
					(size 1.27 1.27)
					(thickness 0.15)
				)
				(justify left bottom)
				(hide yes)
			)
		)
		(property "Footprint" "antmicro-footprints:C_0402_1005Metric"
			(at 240.03 107.95 0)
			(effects
				(font
					(size 1.27 1.27)
					(thickness 0.15)
				)
				(justify left bottom)
				(hide yes)
			)
		)
		(property "Datasheet" "https://product.tdk.com/en/search/capacitor/ceramic/mlcc/info?part_no=C1005X6S1A105K050BC"
			(at 242.57 107.95 0)
			(effects
				(font
					(size 1.27 1.27)
					(thickness 0.15)
				)
				(justify left bottom)
				(hide yes)
			)
		)
		(property "Description" "SMD Multilayer Ceramic Capacitor, 1 µF, 10 V, 0402 [1005 Metric], ± 10%, X6S, C"
			(at 227.33 128.27 0)
			(effects
				(font
					(size 1.27 1.27)
				)
				(hide yes)
			)
		)
		(property "MPN" "C1005X6S1A105K050BC"
			(at 245.11 107.95 0)
			(effects
				(font
					(size 1.27 1.27)
					(thickness 0.15)
				)
				(justify left bottom)
				(hide yes)
			)
		)
		(property "Manufacturer" "TDK"
			(at 247.65 107.95 0)
			(effects
				(font
					(size 1.27 1.27)
					(thickness 0.15)
				)
				(justify left bottom)
				(hide yes)
			)
		)
		(property "License" "Apache-2.0"
			(at 250.19 107.95 0)
			(effects
				(font
					(size 1.27 1.27)
					(thickness 0.15)
				)
				(justify left bottom)
				(hide yes)
			)
		)
		(property "Val" "1u"
			(at 227.965 127.635 90)
			(effects
				(font
					(size 1.27 1.27)
					(thickness 0.15)
				)
				(justify right)
			)
		)
		(property "Voltage" ""
			(at 255.27 107.95 0)
			(effects
				(font
					(size 1.27 1.27)
				)
				(justify left bottom)
				(hide yes)
			)
		)
		(property "Dielectric" ""
			(at 257.81 107.95 0)
			(effects
				(font
					(size 1.27 1.27)
				)
				(justify left bottom)
				(hide yes)
			)
		)
		(property "Author" "Antmicro"
			(at 252.73 107.95 0)
			(effects
				(font
					(size 1.27 1.27)
					(thickness 0.15)
				)
				(justify left bottom)
				(hide yes)
			)
		)
		(pin "1"
		)
		(pin "2"
		)
		(instances
			(project "thunderbolt-to-10gbe-adapter"
				(path ""
					(reference "C76")
					(unit 1)
				)
			)
		)
	)
	(symbol
		(lib_id "antmicropower:GND")
		(at 152.4 96.52 0)
		(unit 1)
		(exclude_from_sim no)
		(in_bom yes)
		(on_board yes)
		(dnp no)
		(property "Reference" "#PWR088"
			(at 152.4 102.87 0)
			(effects
				(font
					(size 1.27 1.27)
				)
				(hide yes)
			)
		)
		(property "Value" "GND"
			(at 152.4 100.33 0)
			(effects
				(font
					(size 1.27 1.27)
				)
			)
		)
		(property "Footprint" ""
			(at 152.4 96.52 0)
			(effects
				(font
					(size 1.27 1.27)
				)
				(hide yes)
			)
		)
		(property "Datasheet" ""
			(at 152.4 96.52 0)
			(effects
				(font
					(size 1.27 1.27)
				)
				(hide yes)
			)
		)
		(property "Description" ""
			(at 152.4 96.52 0)
			(effects
				(font
					(size 1.27 1.27)
				)
				(hide yes)
			)
		)
		(property "Author" "Antmicro"
			(at 161.29 104.14 0)
			(effects
				(font
					(size 1.27 1.27)
					(thickness 0.15)
				)
				(justify left bottom)
				(hide yes)
			)
		)
		(property "License" "Apache-2.0"
			(at 161.29 106.68 0)
			(effects
				(font
					(size 1.27 1.27)
					(thickness 0.15)
				)
				(justify left bottom)
				(hide yes)
			)
		)
		(pin "1"
		)
		(instances
			(project "thunderbolt-to-10gbe-adapter"
				(path ""
					(reference "#PWR088")
					(unit 1)
				)
			)
		)
	)
	(symbol
		(lib_id "antmicroCapacitors0402:C_100n_0402")
		(at 153.67 222.25 90)
		(unit 1)
		(exclude_from_sim no)
		(in_bom yes)
		(on_board yes)
		(dnp no)
		(property "Reference" "C63"
			(at 151.13 217.805 90)
			(effects
				(font
					(size 1.27 1.27)
					(thickness 0.15)
				)
				(justify left)
			)
		)
		(property "Value" "C_100n_0402"
			(at 163.83 201.93 0)
			(effects
				(font
					(size 1.27 1.27)
					(thickness 0.15)
				)
				(justify left bottom)
				(hide yes)
			)
		)
		(property "Footprint" "antmicro-footprints:C_0402_1005Metric"
			(at 166.37 201.93 0)
			(effects
				(font
					(size 1.27 1.27)
					(thickness 0.15)
				)
				(justify left bottom)
				(hide yes)
			)
		)
		(property "Datasheet" "https://www.murata.com/products/productdetail?partno=GRM155R61H104KE14%23"
			(at 168.91 201.93 0)
			(effects
				(font
					(size 1.27 1.27)
					(thickness 0.15)
				)
				(justify left bottom)
				(hide yes)
			)
		)
		(property "Description" "SMD Multilayer Ceramic Capacitor, 0.1 µF, 50 V, 0402 [1005 Metric], ± 10%, X5R, GRM Series"
			(at 153.67 222.25 0)
			(effects
				(font
					(size 1.27 1.27)
				)
				(hide yes)
			)
		)
		(property "MPN" "GRM155R61H104KE14D"
			(at 171.45 201.93 0)
			(effects
				(font
					(size 1.27 1.27)
					(thickness 0.15)
				)
				(justify left bottom)
				(hide yes)
			)
		)
		(property "Manufacturer" "Murata"
			(at 173.99 201.93 0)
			(effects
				(font
					(size 1.27 1.27)
					(thickness 0.15)
				)
				(justify left bottom)
				(hide yes)
			)
		)
		(property "License" "Apache-2.0"
			(at 176.53 201.93 0)
			(effects
				(font
					(size 1.27 1.27)
					(thickness 0.15)
				)
				(justify left bottom)
				(hide yes)
			)
		)
		(property "Val" "100n"
			(at 151.13 220.345 90)
			(effects
				(font
					(size 1.27 1.27)
					(thickness 0.15)
				)
				(justify left)
			)
		)
		(property "Voltage" "50V"
			(at 181.61 201.93 0)
			(effects
				(font
					(size 1.27 1.27)
				)
				(justify left bottom)
				(hide yes)
			)
		)
		(property "Dielectric" "X5R"
			(at 184.15 201.93 0)
			(effects
				(font
					(size 1.27 1.27)
				)
				(justify left bottom)
				(hide yes)
			)
		)
		(property "Author" "Antmicro"
			(at 179.07 201.93 0)
			(effects
				(font
					(size 1.27 1.27)
					(thickness 0.15)
				)
				(justify left bottom)
				(hide yes)
			)
		)
		(pin "1"
		)
		(pin "2"
		)
		(instances
			(project "thunderbolt-to-10gbe-adapter"
				(path ""
					(reference "C63")
					(unit 1)
				)
			)
		)
	)
	(symbol
		(lib_id "antmicropower:GND")
		(at 233.68 129.54 0)
		(unit 1)
		(exclude_from_sim no)
		(in_bom yes)
		(on_board yes)
		(dnp no)
		(property "Reference" "#PWR0112"
			(at 233.68 135.89 0)
			(effects
				(font
					(size 1.27 1.27)
				)
				(hide yes)
			)
		)
		(property "Value" "GND"
			(at 233.68 133.35 0)
			(effects
				(font
					(size 1.27 1.27)
				)
			)
		)
		(property "Footprint" ""
			(at 233.68 129.54 0)
			(effects
				(font
					(size 1.27 1.27)
				)
				(hide yes)
			)
		)
		(property "Datasheet" ""
			(at 233.68 129.54 0)
			(effects
				(font
					(size 1.27 1.27)
				)
				(hide yes)
			)
		)
		(property "Description" ""
			(at 233.68 129.54 0)
			(effects
				(font
					(size 1.27 1.27)
				)
				(hide yes)
			)
		)
		(property "Author" "Antmicro"
			(at 242.57 137.16 0)
			(effects
				(font
					(size 1.27 1.27)
					(thickness 0.15)
				)
				(justify left bottom)
				(hide yes)
			)
		)
		(property "License" "Apache-2.0"
			(at 242.57 139.7 0)
			(effects
				(font
					(size 1.27 1.27)
					(thickness 0.15)
				)
				(justify left bottom)
				(hide yes)
			)
		)
		(pin "1"
		)
		(instances
			(project "thunderbolt-to-10gbe-adapter"
				(path ""
					(reference "#PWR0112")
					(unit 1)
				)
			)
		)
	)
	(symbol
		(lib_id "antmicropower:PWR_FLAG")
		(at 152.4 158.75 90)
		(unit 1)
		(exclude_from_sim no)
		(in_bom yes)
		(on_board yes)
		(dnp no)
		(fields_autoplaced yes)
		(property "Reference" "#FLG013"
			(at 150.495 158.75 0)
			(effects
				(font
					(size 1.27 1.27)
				)
				(hide yes)
			)
		)
		(property "Value" "PWR_FLAG"
			(at 148.59 158.7499 90)
			(effects
				(font
					(size 1.27 1.27)
				)
				(justify left)
			)
		)
		(property "Footprint" ""
			(at 152.4 158.75 0)
			(effects
				(font
					(size 1.27 1.27)
				)
				(hide yes)
			)
		)
		(property "Datasheet" ""
			(at 152.4 158.75 0)
			(effects
				(font
					(size 1.27 1.27)
				)
				(hide yes)
			)
		)
		(property "Description" ""
			(at 154.94 158.75 0)
			(effects
				(font
					(size 1.27 1.27)
				)
				(justify left bottom)
				(hide yes)
			)
		)
		(pin "1"
		)
		(instances
			(project "thunderbolt-to-10gbe-adapter"
				(path ""
					(reference "#FLG013")
					(unit 1)
				)
			)
		)
	)
	(symbol
		(lib_id "antmicropower:PWR_FLAG")
		(at 260.35 120.65 270)
		(unit 1)
		(exclude_from_sim no)
		(in_bom yes)
		(on_board yes)
		(dnp no)
		(fields_autoplaced yes)
		(property "Reference" "#FLG018"
			(at 262.255 120.65 0)
			(effects
				(font
					(size 1.27 1.27)
				)
				(hide yes)
			)
		)
		(property "Value" "PWR_FLAG"
			(at 264.16 120.6499 90)
			(effects
				(font
					(size 1.27 1.27)
				)
				(justify left)
			)
		)
		(property "Footprint" ""
			(at 260.35 120.65 0)
			(effects
				(font
					(size 1.27 1.27)
				)
				(hide yes)
			)
		)
		(property "Datasheet" ""
			(at 260.35 120.65 0)
			(effects
				(font
					(size 1.27 1.27)
				)
				(hide yes)
			)
		)
		(property "Description" ""
			(at 257.81 120.65 0)
			(effects
				(font
					(size 1.27 1.27)
				)
				(justify left bottom)
				(hide yes)
			)
		)
		(pin "1"
		)
		(instances
			(project "thunderbolt-to-10gbe-adapter"
				(path ""
					(reference "#FLG018")
					(unit 1)
				)
			)
		)
	)
	(symbol
		(lib_id "antmicropower:GND")
		(at 246.38 168.91 0)
		(unit 1)
		(exclude_from_sim no)
		(in_bom yes)
		(on_board yes)
		(dnp no)
		(property "Reference" "#PWR0124"
			(at 246.38 175.26 0)
			(effects
				(font
					(size 1.27 1.27)
				)
				(hide yes)
			)
		)
		(property "Value" "GND"
			(at 246.38 172.72 0)
			(effects
				(font
					(size 1.27 1.27)
				)
			)
		)
		(property "Footprint" ""
			(at 246.38 168.91 0)
			(effects
				(font
					(size 1.27 1.27)
				)
				(hide yes)
			)
		)
		(property "Datasheet" ""
			(at 246.38 168.91 0)
			(effects
				(font
					(size 1.27 1.27)
				)
				(hide yes)
			)
		)
		(property "Description" ""
			(at 246.38 168.91 0)
			(effects
				(font
					(size 1.27 1.27)
				)
				(hide yes)
			)
		)
		(property "Author" "Antmicro"
			(at 255.27 176.53 0)
			(effects
				(font
					(size 1.27 1.27)
					(thickness 0.15)
				)
				(justify left bottom)
				(hide yes)
			)
		)
		(property "License" "Apache-2.0"
			(at 255.27 179.07 0)
			(effects
				(font
					(size 1.27 1.27)
					(thickness 0.15)
				)
				(justify left bottom)
				(hide yes)
			)
		)
		(pin "1"
		)
		(instances
			(project "thunderbolt-to-10gbe-adapter"
				(path ""
					(reference "#PWR0124")
					(unit 1)
				)
			)
		)
	)
	(symbol
		(lib_id "antmicroCapacitors0402:C_100n_0402")
		(at 246.38 110.49 90)
		(unit 1)
		(exclude_from_sim no)
		(in_bom yes)
		(on_board yes)
		(dnp no)
		(property "Reference" "C87"
			(at 247.015 106.045 90)
			(effects
				(font
					(size 1.27 1.27)
					(thickness 0.15)
				)
				(justify right)
			)
		)
		(property "Value" "C_100n_0402"
			(at 256.54 90.17 0)
			(effects
				(font
					(size 1.27 1.27)
					(thickness 0.15)
				)
				(justify left bottom)
				(hide yes)
			)
		)
		(property "Footprint" "antmicro-footprints:C_0402_1005Metric"
			(at 259.08 90.17 0)
			(effects
				(font
					(size 1.27 1.27)
					(thickness 0.15)
				)
				(justify left bottom)
				(hide yes)
			)
		)
		(property "Datasheet" "https://www.murata.com/products/productdetail?partno=GRM155R61H104KE14%23"
			(at 261.62 90.17 0)
			(effects
				(font
					(size 1.27 1.27)
					(thickness 0.15)
				)
				(justify left bottom)
				(hide yes)
			)
		)
		(property "Description" "SMD Multilayer Ceramic Capacitor, 0.1 µF, 50 V, 0402 [1005 Metric], ± 10%, X5R, GRM Series"
			(at 246.38 110.49 0)
			(effects
				(font
					(size 1.27 1.27)
				)
				(hide yes)
			)
		)
		(property "MPN" "GRM155R61H104KE14D"
			(at 264.16 90.17 0)
			(effects
				(font
					(size 1.27 1.27)
					(thickness 0.15)
				)
				(justify left bottom)
				(hide yes)
			)
		)
		(property "Manufacturer" "Murata"
			(at 266.7 90.17 0)
			(effects
				(font
					(size 1.27 1.27)
					(thickness 0.15)
				)
				(justify left bottom)
				(hide yes)
			)
		)
		(property "License" "Apache-2.0"
			(at 269.24 90.17 0)
			(effects
				(font
					(size 1.27 1.27)
					(thickness 0.15)
				)
				(justify left bottom)
				(hide yes)
			)
		)
		(property "Val" "100n"
			(at 247.015 109.855 90)
			(effects
				(font
					(size 1.27 1.27)
					(thickness 0.15)
				)
				(justify right)
			)
		)
		(property "Voltage" "50V"
			(at 274.32 90.17 0)
			(effects
				(font
					(size 1.27 1.27)
				)
				(justify left bottom)
				(hide yes)
			)
		)
		(property "Dielectric" "X5R"
			(at 276.86 90.17 0)
			(effects
				(font
					(size 1.27 1.27)
				)
				(justify left bottom)
				(hide yes)
			)
		)
		(property "Author" "Antmicro"
			(at 271.78 90.17 0)
			(effects
				(font
					(size 1.27 1.27)
					(thickness 0.15)
				)
				(justify left bottom)
				(hide yes)
			)
		)
		(pin "1"
		)
		(pin "2"
		)
		(instances
			(project "thunderbolt-to-10gbe-adapter"
				(path ""
					(reference "C87")
					(unit 1)
				)
			)
		)
	)
	(symbol
		(lib_id "antmicropower:GND")
		(at 243.84 227.33 0)
		(unit 1)
		(exclude_from_sim no)
		(in_bom yes)
		(on_board yes)
		(dnp no)
		(property "Reference" "#PWR0119"
			(at 243.84 233.68 0)
			(effects
				(font
					(size 1.27 1.27)
				)
				(hide yes)
			)
		)
		(property "Value" "GND"
			(at 243.84 231.14 0)
			(effects
				(font
					(size 1.27 1.27)
				)
			)
		)
		(property "Footprint" ""
			(at 243.84 227.33 0)
			(effects
				(font
					(size 1.27 1.27)
				)
				(hide yes)
			)
		)
		(property "Datasheet" ""
			(at 243.84 227.33 0)
			(effects
				(font
					(size 1.27 1.27)
				)
				(hide yes)
			)
		)
		(property "Description" ""
			(at 243.84 227.33 0)
			(effects
				(font
					(size 1.27 1.27)
				)
				(hide yes)
			)
		)
		(property "Author" "Antmicro"
			(at 252.73 234.95 0)
			(effects
				(font
					(size 1.27 1.27)
					(thickness 0.15)
				)
				(justify left bottom)
				(hide yes)
			)
		)
		(property "License" "Apache-2.0"
			(at 252.73 237.49 0)
			(effects
				(font
					(size 1.27 1.27)
					(thickness 0.15)
				)
				(justify left bottom)
				(hide yes)
			)
		)
		(pin "1"
		)
		(instances
			(project "thunderbolt-to-10gbe-adapter"
				(path ""
					(reference "#PWR0119")
					(unit 1)
				)
			)
		)
	)
	(symbol
		(lib_id "antmicropower:GND")
		(at 252.73 80.01 0)
		(unit 1)
		(exclude_from_sim no)
		(in_bom yes)
		(on_board yes)
		(dnp no)
		(property "Reference" "#PWR0136"
			(at 252.73 86.36 0)
			(effects
				(font
					(size 1.27 1.27)
				)
				(hide yes)
			)
		)
		(property "Value" "GND"
			(at 252.73 83.82 0)
			(effects
				(font
					(size 1.27 1.27)
				)
			)
		)
		(property "Footprint" ""
			(at 252.73 80.01 0)
			(effects
				(font
					(size 1.27 1.27)
				)
				(hide yes)
			)
		)
		(property "Datasheet" ""
			(at 252.73 80.01 0)
			(effects
				(font
					(size 1.27 1.27)
				)
				(hide yes)
			)
		)
		(property "Description" ""
			(at 252.73 80.01 0)
			(effects
				(font
					(size 1.27 1.27)
				)
				(hide yes)
			)
		)
		(property "Author" "Antmicro"
			(at 261.62 87.63 0)
			(effects
				(font
					(size 1.27 1.27)
					(thickness 0.15)
				)
				(justify left bottom)
				(hide yes)
			)
		)
		(property "License" "Apache-2.0"
			(at 261.62 90.17 0)
			(effects
				(font
					(size 1.27 1.27)
					(thickness 0.15)
				)
				(justify left bottom)
				(hide yes)
			)
		)
		(pin "1"
		)
		(instances
			(project "thunderbolt-to-10gbe-adapter"
				(path ""
					(reference "#PWR0136")
					(unit 1)
				)
			)
		)
	)
	(symbol
		(lib_id "antmicropower:+3V3")
		(at 153.67 213.36 0)
		(unit 1)
		(exclude_from_sim no)
		(in_bom yes)
		(on_board yes)
		(dnp no)
		(property "Reference" "#PWR092"
			(at 168.91 213.36 0)
			(effects
				(font
					(size 1.27 1.27)
					(thickness 0.15)
				)
				(justify left bottom)
				(hide yes)
			)
		)
		(property "Value" "+3V3_TB"
			(at 153.67 209.55 0)
			(effects
				(font
					(size 1.27 1.27)
					(thickness 0.15)
				)
			)
		)
		(property "Footprint" ""
			(at 168.91 220.98 0)
			(effects
				(font
					(size 1.27 1.27)
					(thickness 0.15)
				)
				(justify left bottom)
				(hide yes)
			)
		)
		(property "Datasheet" ""
			(at 168.91 223.52 0)
			(effects
				(font
					(size 1.27 1.27)
					(thickness 0.15)
				)
				(justify left bottom)
				(hide yes)
			)
		)
		(property "Description" ""
			(at 168.91 226.06 0)
			(effects
				(font
					(size 1.27 1.27)
				)
				(justify left bottom)
				(hide yes)
			)
		)
		(property "Author" "Antmicro"
			(at 168.91 215.9 0)
			(effects
				(font
					(size 1.27 1.27)
					(thickness 0.15)
				)
				(justify left bottom)
				(hide yes)
			)
		)
		(property "License" "Apache-2.0"
			(at 168.91 218.44 0)
			(effects
				(font
					(size 1.27 1.27)
					(thickness 0.15)
				)
				(justify left bottom)
				(hide yes)
			)
		)
		(pin "1"
		)
		(instances
			(project "thunderbolt-to-10gbe-adapter"
				(path ""
					(reference "#PWR092")
					(unit 1)
				)
			)
		)
	)
	(symbol
		(lib_id "antmicroCapacitors0402:C_100n_0402")
		(at 246.38 78.74 90)
		(unit 1)
		(exclude_from_sim no)
		(in_bom yes)
		(on_board yes)
		(dnp no)
		(property "Reference" "C96"
			(at 247.015 74.295 90)
			(effects
				(font
					(size 1.27 1.27)
					(thickness 0.15)
				)
				(justify right)
			)
		)
		(property "Value" "C_100n_0402"
			(at 256.54 58.42 0)
			(effects
				(font
					(size 1.27 1.27)
					(thickness 0.15)
				)
				(justify left bottom)
				(hide yes)
			)
		)
		(property "Footprint" "antmicro-footprints:C_0402_1005Metric"
			(at 259.08 58.42 0)
			(effects
				(font
					(size 1.27 1.27)
					(thickness 0.15)
				)
				(justify left bottom)
				(hide yes)
			)
		)
		(property "Datasheet" "https://www.murata.com/products/productdetail?partno=GRM155R61H104KE14%23"
			(at 261.62 58.42 0)
			(effects
				(font
					(size 1.27 1.27)
					(thickness 0.15)
				)
				(justify left bottom)
				(hide yes)
			)
		)
		(property "Description" "SMD Multilayer Ceramic Capacitor, 0.1 µF, 50 V, 0402 [1005 Metric], ± 10%, X5R, GRM Series"
			(at 246.38 78.74 0)
			(effects
				(font
					(size 1.27 1.27)
				)
				(hide yes)
			)
		)
		(property "MPN" "GRM155R61H104KE14D"
			(at 264.16 58.42 0)
			(effects
				(font
					(size 1.27 1.27)
					(thickness 0.15)
				)
				(justify left bottom)
				(hide yes)
			)
		)
		(property "Manufacturer" "Murata"
			(at 266.7 58.42 0)
			(effects
				(font
					(size 1.27 1.27)
					(thickness 0.15)
				)
				(justify left bottom)
				(hide yes)
			)
		)
		(property "License" "Apache-2.0"
			(at 269.24 58.42 0)
			(effects
				(font
					(size 1.27 1.27)
					(thickness 0.15)
				)
				(justify left bottom)
				(hide yes)
			)
		)
		(property "Val" "100n"
			(at 247.015 78.105 90)
			(effects
				(font
					(size 1.27 1.27)
					(thickness 0.15)
				)
				(justify right)
			)
		)
		(property "Voltage" "50V"
			(at 274.32 58.42 0)
			(effects
				(font
					(size 1.27 1.27)
				)
				(justify left bottom)
				(hide yes)
			)
		)
		(property "Dielectric" "X5R"
			(at 276.86 58.42 0)
			(effects
				(font
					(size 1.27 1.27)
				)
				(justify left bottom)
				(hide yes)
			)
		)
		(property "Author" "Antmicro"
			(at 271.78 58.42 0)
			(effects
				(font
					(size 1.27 1.27)
					(thickness 0.15)
				)
				(justify left bottom)
				(hide yes)
			)
		)
		(pin "1"
		)
		(pin "2"
		)
		(instances
			(project "thunderbolt-to-10gbe-adapter"
				(path ""
					(reference "C96")
					(unit 1)
				)
			)
		)
	)
	(symbol
		(lib_id "antmicropower:GND")
		(at 233.68 97.79 0)
		(unit 1)
		(exclude_from_sim no)
		(in_bom yes)
		(on_board yes)
		(dnp no)
		(property "Reference" "#PWR0111"
			(at 233.68 104.14 0)
			(effects
				(font
					(size 1.27 1.27)
				)
				(hide yes)
			)
		)
		(property "Value" "GND"
			(at 233.68 101.6 0)
			(effects
				(font
					(size 1.27 1.27)
				)
			)
		)
		(property "Footprint" ""
			(at 233.68 97.79 0)
			(effects
				(font
					(size 1.27 1.27)
				)
				(hide yes)
			)
		)
		(property "Datasheet" ""
			(at 233.68 97.79 0)
			(effects
				(font
					(size 1.27 1.27)
				)
				(hide yes)
			)
		)
		(property "Description" ""
			(at 233.68 97.79 0)
			(effects
				(font
					(size 1.27 1.27)
				)
				(hide yes)
			)
		)
		(property "Author" "Antmicro"
			(at 242.57 105.41 0)
			(effects
				(font
					(size 1.27 1.27)
					(thickness 0.15)
				)
				(justify left bottom)
				(hide yes)
			)
		)
		(property "License" "Apache-2.0"
			(at 242.57 107.95 0)
			(effects
				(font
					(size 1.27 1.27)
					(thickness 0.15)
				)
				(justify left bottom)
				(hide yes)
			)
		)
		(pin "1"
		)
		(instances
			(project "thunderbolt-to-10gbe-adapter"
				(path ""
					(reference "#PWR0111")
					(unit 1)
				)
			)
		)
	)
	(symbol
		(lib_id "antmicroCapacitors0402:C_1u_0402")
		(at 162.56 93.98 90)
		(unit 1)
		(exclude_from_sim no)
		(in_bom yes)
		(on_board yes)
		(dnp no)
		(property "Reference" "C69"
			(at 163.195 89.535 90)
			(effects
				(font
					(size 1.27 1.27)
					(thickness 0.15)
				)
				(justify right)
			)
		)
		(property "Value" "C_1u_0402"
			(at 172.72 73.66 0)
			(effects
				(font
					(size 1.27 1.27)
					(thickness 0.15)
				)
				(justify left bottom)
				(hide yes)
			)
		)
		(property "Footprint" "antmicro-footprints:C_0402_1005Metric"
			(at 175.26 73.66 0)
			(effects
				(font
					(size 1.27 1.27)
					(thickness 0.15)
				)
				(justify left bottom)
				(hide yes)
			)
		)
		(property "Datasheet" "https://product.tdk.com/en/search/capacitor/ceramic/mlcc/info?part_no=C1005X6S1A105K050BC"
			(at 177.8 73.66 0)
			(effects
				(font
					(size 1.27 1.27)
					(thickness 0.15)
				)
				(justify left bottom)
				(hide yes)
			)
		)
		(property "Description" "SMD Multilayer Ceramic Capacitor, 1 µF, 10 V, 0402 [1005 Metric], ± 10%, X6S, C"
			(at 162.56 93.98 0)
			(effects
				(font
					(size 1.27 1.27)
				)
				(hide yes)
			)
		)
		(property "MPN" "C1005X6S1A105K050BC"
			(at 180.34 73.66 0)
			(effects
				(font
					(size 1.27 1.27)
					(thickness 0.15)
				)
				(justify left bottom)
				(hide yes)
			)
		)
		(property "Manufacturer" "TDK"
			(at 182.88 73.66 0)
			(effects
				(font
					(size 1.27 1.27)
					(thickness 0.15)
				)
				(justify left bottom)
				(hide yes)
			)
		)
		(property "License" "Apache-2.0"
			(at 185.42 73.66 0)
			(effects
				(font
					(size 1.27 1.27)
					(thickness 0.15)
				)
				(justify left bottom)
				(hide yes)
			)
		)
		(property "Val" "1u"
			(at 163.195 93.345 90)
			(effects
				(font
					(size 1.27 1.27)
					(thickness 0.15)
				)
				(justify right)
			)
		)
		(property "Voltage" ""
			(at 190.5 73.66 0)
			(effects
				(font
					(size 1.27 1.27)
				)
				(justify left bottom)
				(hide yes)
			)
		)
		(property "Dielectric" ""
			(at 193.04 73.66 0)
			(effects
				(font
					(size 1.27 1.27)
				)
				(justify left bottom)
				(hide yes)
			)
		)
		(property "Author" "Antmicro"
			(at 187.96 73.66 0)
			(effects
				(font
					(size 1.27 1.27)
					(thickness 0.15)
				)
				(justify left bottom)
				(hide yes)
			)
		)
		(pin "1"
		)
		(pin "2"
		)
		(instances
			(project "thunderbolt-to-10gbe-adapter"
				(path ""
					(reference "C69")
					(unit 1)
				)
			)
		)
	)
	(symbol
		(lib_id "antmicropower:GND")
		(at 152.4 148.59 0)
		(unit 1)
		(exclude_from_sim no)
		(in_bom yes)
		(on_board yes)
		(dnp no)
		(property "Reference" "#PWR090"
			(at 152.4 154.94 0)
			(effects
				(font
					(size 1.27 1.27)
				)
				(hide yes)
			)
		)
		(property "Value" "GND"
			(at 152.4 152.4 0)
			(effects
				(font
					(size 1.27 1.27)
				)
			)
		)
		(property "Footprint" ""
			(at 152.4 148.59 0)
			(effects
				(font
					(size 1.27 1.27)
				)
				(hide yes)
			)
		)
		(property "Datasheet" ""
			(at 152.4 148.59 0)
			(effects
				(font
					(size 1.27 1.27)
				)
				(hide yes)
			)
		)
		(property "Description" ""
			(at 152.4 148.59 0)
			(effects
				(font
					(size 1.27 1.27)
				)
				(hide yes)
			)
		)
		(property "Author" "Antmicro"
			(at 161.29 156.21 0)
			(effects
				(font
					(size 1.27 1.27)
					(thickness 0.15)
				)
				(justify left bottom)
				(hide yes)
			)
		)
		(property "License" "Apache-2.0"
			(at 161.29 158.75 0)
			(effects
				(font
					(size 1.27 1.27)
					(thickness 0.15)
				)
				(justify left bottom)
				(hide yes)
			)
		)
		(pin "1"
		)
		(instances
			(project "thunderbolt-to-10gbe-adapter"
				(path ""
					(reference "#PWR090")
					(unit 1)
				)
			)
		)
	)
	(symbol
		(lib_id "antmicropower:PWR_FLAG")
		(at 134.62 137.16 0)
		(mirror y)
		(unit 1)
		(exclude_from_sim no)
		(in_bom yes)
		(on_board yes)
		(dnp no)
		(property "Reference" "#FLG010"
			(at 134.62 135.255 0)
			(effects
				(font
					(size 1.27 1.27)
				)
				(hide yes)
			)
		)
		(property "Value" "PWR_FLAG"
			(at 144.145 139.7 0)
			(effects
				(font
					(size 1.27 1.27)
				)
				(justify left)
			)
		)
		(property "Footprint" ""
			(at 134.62 137.16 0)
			(effects
				(font
					(size 1.27 1.27)
				)
				(hide yes)
			)
		)
		(property "Datasheet" ""
			(at 134.62 137.16 0)
			(effects
				(font
					(size 1.27 1.27)
				)
				(hide yes)
			)
		)
		(property "Description" ""
			(at 134.62 137.16 0)
			(effects
				(font
					(size 1.27 1.27)
				)
				(hide yes)
			)
		)
		(pin "1"
		)
		(instances
			(project "thunderbolt-to-10gbe-adapter"
				(path ""
					(reference "#FLG010")
					(unit 1)
				)
			)
		)
	)
	(symbol
		(lib_id "antmicropower:PWR_FLAG")
		(at 255.27 101.6 0)
		(unit 1)
		(exclude_from_sim no)
		(in_bom yes)
		(on_board yes)
		(dnp no)
		(property "Reference" "#FLG017"
			(at 255.27 99.695 0)
			(effects
				(font
					(size 1.27 1.27)
				)
				(hide yes)
			)
		)
		(property "Value" "PWR_FLAG"
			(at 255.27 97.79 0)
			(effects
				(font
					(size 1.27 1.27)
				)
			)
		)
		(property "Footprint" ""
			(at 255.27 101.6 0)
			(effects
				(font
					(size 1.27 1.27)
				)
				(hide yes)
			)
		)
		(property "Datasheet" ""
			(at 255.27 101.6 0)
			(effects
				(font
					(size 1.27 1.27)
				)
				(hide yes)
			)
		)
		(property "Description" ""
			(at 255.27 104.14 0)
			(effects
				(font
					(size 1.27 1.27)
				)
				(justify left bottom)
				(hide yes)
			)
		)
		(pin "1"
		)
		(instances
			(project "thunderbolt-to-10gbe-adapter"
				(path ""
					(reference "#FLG017")
					(unit 1)
				)
			)
		)
	)
	(symbol
		(lib_id "antmicropower:PWR_FLAG")
		(at 137.16 102.87 90)
		(unit 1)
		(exclude_from_sim no)
		(in_bom yes)
		(on_board yes)
		(dnp no)
		(fields_autoplaced yes)
		(property "Reference" "#FLG011"
			(at 135.255 102.87 0)
			(effects
				(font
					(size 1.27 1.27)
				)
				(hide yes)
			)
		)
		(property "Value" "PWR_FLAG"
			(at 133.35 102.8699 90)
			(effects
				(font
					(size 1.27 1.27)
				)
				(justify left)
			)
		)
		(property "Footprint" ""
			(at 137.16 102.87 0)
			(effects
				(font
					(size 1.27 1.27)
				)
				(hide yes)
			)
		)
		(property "Datasheet" ""
			(at 137.16 102.87 0)
			(effects
				(font
					(size 1.27 1.27)
				)
				(hide yes)
			)
		)
		(property "Description" ""
			(at 139.7 102.87 0)
			(effects
				(font
					(size 1.27 1.27)
				)
				(justify left bottom)
				(hide yes)
			)
		)
		(pin "1"
		)
		(instances
			(project "thunderbolt-to-10gbe-adapter"
				(path ""
					(reference "#FLG011")
					(unit 1)
				)
			)
		)
	)
	(symbol
		(lib_id "antmicroResistors0402:R_1k_0402")
		(at 236.22 217.17 0)
		(unit 1)
		(exclude_from_sim no)
		(in_bom yes)
		(on_board yes)
		(dnp no)
		(property "Reference" "R72"
			(at 238.76 215.265 0)
			(effects
				(font
					(size 1.27 1.27)
					(thickness 0.15)
				)
			)
		)
		(property "Value" "R_1k_0402"
			(at 256.54 229.87 0)
			(effects
				(font
					(size 1.27 1.27)
					(thickness 0.15)
				)
				(justify left bottom)
				(hide yes)
			)
		)
		(property "Footprint" "antmicro-footprints:R_0402_1005Metric"
			(at 256.54 232.41 0)
			(effects
				(font
					(size 1.27 1.27)
					(thickness 0.15)
				)
				(justify left bottom)
				(hide yes)
			)
		)
		(property "Datasheet" "https://www.bourns.com/docs/product-datasheets/cr.pdf"
			(at 256.54 234.95 0)
			(effects
				(font
					(size 1.27 1.27)
					(thickness 0.15)
				)
				(justify left bottom)
				(hide yes)
			)
		)
		(property "Description" "SMD Chip Resistor, 1 kohm, ± 1%, 63 mW, 0402 [1005 Metric], Thick Film, General Purpose"
			(at 236.22 217.17 0)
			(effects
				(font
					(size 1.27 1.27)
				)
				(hide yes)
			)
		)
		(property "MPN" "CR0402-FX-1001GLF"
			(at 256.54 237.49 0)
			(effects
				(font
					(size 1.27 1.27)
					(thickness 0.15)
				)
				(justify left bottom)
				(hide yes)
			)
		)
		(property "Manufacturer" "Bourns"
			(at 256.54 240.03 0)
			(effects
				(font
					(size 1.27 1.27)
					(thickness 0.15)
				)
				(justify left bottom)
				(hide yes)
			)
		)
		(property "License" "Apache-2.0"
			(at 256.54 242.57 0)
			(effects
				(font
					(size 1.27 1.27)
					(thickness 0.15)
				)
				(justify left bottom)
				(hide yes)
			)
		)
		(property "Val" "1k"
			(at 238.76 219.075 0)
			(effects
				(font
					(size 1.27 1.27)
					(thickness 0.15)
				)
			)
		)
		(property "Tolerance" "1%"
			(at 256.54 227.33 0)
			(effects
				(font
					(size 1.27 1.27)
				)
				(justify left bottom)
				(hide yes)
			)
		)
		(property "Author" "Antmicro"
			(at 256.54 245.11 0)
			(effects
				(font
					(size 1.27 1.27)
					(thickness 0.15)
				)
				(justify left bottom)
				(hide yes)
			)
		)
		(pin "1"
		)
		(pin "2"
		)
		(instances
			(project "thunderbolt-to-10gbe-adapter"
				(path ""
					(reference "R72")
					(unit 1)
				)
			)
		)
	)
	(symbol
		(lib_id "antmicroCapacitors0402:C_10u_0402")
		(at 252.73 78.74 90)
		(unit 1)
		(exclude_from_sim no)
		(in_bom yes)
		(on_board yes)
		(dnp no)
		(property "Reference" "C98"
			(at 253.365 74.295 90)
			(effects
				(font
					(size 1.27 1.27)
					(thickness 0.15)
				)
				(justify right)
			)
		)
		(property "Value" "C_10u_0402"
			(at 262.89 58.42 0)
			(effects
				(font
					(size 1.27 1.27)
					(thickness 0.15)
				)
				(justify left bottom)
				(hide yes)
			)
		)
		(property "Footprint" "antmicro-footprints:C_0402_1005Metric"
			(at 265.43 58.42 0)
			(effects
				(font
					(size 1.27 1.27)
					(thickness 0.15)
				)
				(justify left bottom)
				(hide yes)
			)
		)
		(property "Datasheet" "https://www.yageo.com/en/Chart/Download/pdf/CC0402MRX5R5BB106"
			(at 267.97 58.42 0)
			(effects
				(font
					(size 1.27 1.27)
					(thickness 0.15)
				)
				(justify left bottom)
				(hide yes)
			)
		)
		(property "Description" "SMD Multilayer Ceramic Capacitor, 10 µF, 6.3 V, 0402 [1005 Metric], ± 20%, X5R, CC Series"
			(at 252.73 78.74 0)
			(effects
				(font
					(size 1.27 1.27)
				)
				(hide yes)
			)
		)
		(property "MPN" "CC0402MRX5R5BB106"
			(at 270.51 58.42 0)
			(effects
				(font
					(size 1.27 1.27)
					(thickness 0.15)
				)
				(justify left bottom)
				(hide yes)
			)
		)
		(property "Manufacturer" "YAGEO"
			(at 273.05 58.42 0)
			(effects
				(font
					(size 1.27 1.27)
					(thickness 0.15)
				)
				(justify left bottom)
				(hide yes)
			)
		)
		(property "License" "Apache-2.0"
			(at 275.59 58.42 0)
			(effects
				(font
					(size 1.27 1.27)
					(thickness 0.15)
				)
				(justify left bottom)
				(hide yes)
			)
		)
		(property "Val" "10u"
			(at 253.365 78.105 90)
			(effects
				(font
					(size 1.27 1.27)
					(thickness 0.15)
				)
				(justify right)
			)
		)
		(property "Voltage" ""
			(at 280.67 58.42 0)
			(effects
				(font
					(size 1.27 1.27)
				)
				(justify left bottom)
				(hide yes)
			)
		)
		(property "Dielectric" ""
			(at 283.21 58.42 0)
			(effects
				(font
					(size 1.27 1.27)
				)
				(justify left bottom)
				(hide yes)
			)
		)
		(property "Author" "Antmicro"
			(at 278.13 58.42 0)
			(effects
				(font
					(size 1.27 1.27)
					(thickness 0.15)
				)
				(justify left bottom)
				(hide yes)
			)
		)
		(pin "1"
		)
		(pin "2"
		)
		(instances
			(project "thunderbolt-to-10gbe-adapter"
				(path ""
					(reference "C98")
					(unit 1)
				)
			)
		)
	)
	(symbol
		(lib_id "antmicroCapacitors0402:C_1u_0402")
		(at 162.56 129.54 90)
		(unit 1)
		(exclude_from_sim no)
		(in_bom yes)
		(on_board yes)
		(dnp no)
		(fields_autoplaced yes)
		(property "Reference" "C71"
			(at 165.1 125.7236 90)
			(effects
				(font
					(size 1.27 1.27)
					(thickness 0.15)
				)
				(justify right)
			)
		)
		(property "Value" "C_1u_0402"
			(at 172.72 109.22 0)
			(effects
				(font
					(size 1.27 1.27)
					(thickness 0.15)
				)
				(justify left bottom)
				(hide yes)
			)
		)
		(property "Footprint" "antmicro-footprints:C_0402_1005Metric"
			(at 175.26 109.22 0)
			(effects
				(font
					(size 1.27 1.27)
					(thickness 0.15)
				)
				(justify left bottom)
				(hide yes)
			)
		)
		(property "Datasheet" "https://product.tdk.com/en/search/capacitor/ceramic/mlcc/info?part_no=C1005X6S1A105K050BC"
			(at 177.8 109.22 0)
			(effects
				(font
					(size 1.27 1.27)
					(thickness 0.15)
				)
				(justify left bottom)
				(hide yes)
			)
		)
		(property "Description" "SMD Multilayer Ceramic Capacitor, 1 µF, 10 V, 0402 [1005 Metric], ± 10%, X6S, C"
			(at 162.56 129.54 0)
			(effects
				(font
					(size 1.27 1.27)
				)
				(hide yes)
			)
		)
		(property "MPN" "C1005X6S1A105K050BC"
			(at 180.34 109.22 0)
			(effects
				(font
					(size 1.27 1.27)
					(thickness 0.15)
				)
				(justify left bottom)
				(hide yes)
			)
		)
		(property "Manufacturer" "TDK"
			(at 182.88 109.22 0)
			(effects
				(font
					(size 1.27 1.27)
					(thickness 0.15)
				)
				(justify left bottom)
				(hide yes)
			)
		)
		(property "License" "Apache-2.0"
			(at 185.42 109.22 0)
			(effects
				(font
					(size 1.27 1.27)
					(thickness 0.15)
				)
				(justify left bottom)
				(hide yes)
			)
		)
		(property "Val" "1u"
			(at 165.1 128.2636 90)
			(effects
				(font
					(size 1.27 1.27)
					(thickness 0.15)
				)
				(justify right)
			)
		)
		(property "Voltage" ""
			(at 190.5 109.22 0)
			(effects
				(font
					(size 1.27 1.27)
				)
				(justify left bottom)
				(hide yes)
			)
		)
		(property "Dielectric" ""
			(at 193.04 109.22 0)
			(effects
				(font
					(size 1.27 1.27)
				)
				(justify left bottom)
				(hide yes)
			)
		)
		(property "Author" "Antmicro"
			(at 187.96 109.22 0)
			(effects
				(font
					(size 1.27 1.27)
					(thickness 0.15)
				)
				(justify left bottom)
				(hide yes)
			)
		)
		(pin "1"
		)
		(pin "2"
		)
		(instances
			(project "thunderbolt-to-10gbe-adapter"
				(path ""
					(reference "C71")
					(unit 1)
				)
			)
		)
	)
	(symbol
		(lib_id "antmicroCapacitors0402:C_1u_0402")
		(at 152.4 111.76 90)
		(unit 1)
		(exclude_from_sim no)
		(in_bom yes)
		(on_board yes)
		(dnp no)
		(property "Reference" "C60"
			(at 153.035 107.315 90)
			(effects
				(font
					(size 1.27 1.27)
					(thickness 0.15)
				)
				(justify right)
			)
		)
		(property "Value" "C_1u_0402"
			(at 162.56 91.44 0)
			(effects
				(font
					(size 1.27 1.27)
					(thickness 0.15)
				)
				(justify left bottom)
				(hide yes)
			)
		)
		(property "Footprint" "antmicro-footprints:C_0402_1005Metric"
			(at 165.1 91.44 0)
			(effects
				(font
					(size 1.27 1.27)
					(thickness 0.15)
				)
				(justify left bottom)
				(hide yes)
			)
		)
		(property "Datasheet" "https://product.tdk.com/en/search/capacitor/ceramic/mlcc/info?part_no=C1005X6S1A105K050BC"
			(at 167.64 91.44 0)
			(effects
				(font
					(size 1.27 1.27)
					(thickness 0.15)
				)
				(justify left bottom)
				(hide yes)
			)
		)
		(property "Description" "SMD Multilayer Ceramic Capacitor, 1 µF, 10 V, 0402 [1005 Metric], ± 10%, X6S, C"
			(at 152.4 111.76 0)
			(effects
				(font
					(size 1.27 1.27)
				)
				(hide yes)
			)
		)
		(property "MPN" "C1005X6S1A105K050BC"
			(at 170.18 91.44 0)
			(effects
				(font
					(size 1.27 1.27)
					(thickness 0.15)
				)
				(justify left bottom)
				(hide yes)
			)
		)
		(property "Manufacturer" "TDK"
			(at 172.72 91.44 0)
			(effects
				(font
					(size 1.27 1.27)
					(thickness 0.15)
				)
				(justify left bottom)
				(hide yes)
			)
		)
		(property "License" "Apache-2.0"
			(at 175.26 91.44 0)
			(effects
				(font
					(size 1.27 1.27)
					(thickness 0.15)
				)
				(justify left bottom)
				(hide yes)
			)
		)
		(property "Val" "1u"
			(at 153.035 111.125 90)
			(effects
				(font
					(size 1.27 1.27)
					(thickness 0.15)
				)
				(justify right)
			)
		)
		(property "Voltage" ""
			(at 180.34 91.44 0)
			(effects
				(font
					(size 1.27 1.27)
				)
				(justify left bottom)
				(hide yes)
			)
		)
		(property "Dielectric" ""
			(at 182.88 91.44 0)
			(effects
				(font
					(size 1.27 1.27)
				)
				(justify left bottom)
				(hide yes)
			)
		)
		(property "Author" "Antmicro"
			(at 177.8 91.44 0)
			(effects
				(font
					(size 1.27 1.27)
					(thickness 0.15)
				)
				(justify left bottom)
				(hide yes)
			)
		)
		(pin "1"
		)
		(pin "2"
		)
		(instances
			(project "thunderbolt-to-10gbe-adapter"
				(path ""
					(reference "C60")
					(unit 1)
				)
			)
		)
	)
	(symbol
		(lib_id "antmicropower:GND")
		(at 161.29 168.91 0)
		(unit 1)
		(exclude_from_sim no)
		(in_bom yes)
		(on_board yes)
		(dnp no)
		(property "Reference" "#PWR098"
			(at 161.29 175.26 0)
			(effects
				(font
					(size 1.27 1.27)
				)
				(hide yes)
			)
		)
		(property "Value" "GND"
			(at 161.29 172.72 0)
			(effects
				(font
					(size 1.27 1.27)
				)
			)
		)
		(property "Footprint" ""
			(at 161.29 168.91 0)
			(effects
				(font
					(size 1.27 1.27)
				)
				(hide yes)
			)
		)
		(property "Datasheet" ""
			(at 161.29 168.91 0)
			(effects
				(font
					(size 1.27 1.27)
				)
				(hide yes)
			)
		)
		(property "Description" ""
			(at 161.29 168.91 0)
			(effects
				(font
					(size 1.27 1.27)
				)
				(hide yes)
			)
		)
		(property "Author" "Antmicro"
			(at 170.18 176.53 0)
			(effects
				(font
					(size 1.27 1.27)
					(thickness 0.15)
				)
				(justify left bottom)
				(hide yes)
			)
		)
		(property "License" "Apache-2.0"
			(at 170.18 179.07 0)
			(effects
				(font
					(size 1.27 1.27)
					(thickness 0.15)
				)
				(justify left bottom)
				(hide yes)
			)
		)
		(pin "1"
		)
		(instances
			(project "thunderbolt-to-10gbe-adapter"
				(path ""
					(reference "#PWR098")
					(unit 1)
				)
			)
		)
	)
	(symbol
		(lib_id "antmicroCapacitors0402:C_1u_0402")
		(at 147.32 147.32 90)
		(unit 1)
		(exclude_from_sim no)
		(in_bom yes)
		(on_board yes)
		(dnp no)
		(property "Reference" "C58"
			(at 147.955 142.875 90)
			(effects
				(font
					(size 1.27 1.27)
					(thickness 0.15)
				)
				(justify right)
			)
		)
		(property "Value" "C_1u_0402"
			(at 157.48 127 0)
			(effects
				(font
					(size 1.27 1.27)
					(thickness 0.15)
				)
				(justify left bottom)
				(hide yes)
			)
		)
		(property "Footprint" "antmicro-footprints:C_0402_1005Metric"
			(at 160.02 127 0)
			(effects
				(font
					(size 1.27 1.27)
					(thickness 0.15)
				)
				(justify left bottom)
				(hide yes)
			)
		)
		(property "Datasheet" "https://product.tdk.com/en/search/capacitor/ceramic/mlcc/info?part_no=C1005X6S1A105K050BC"
			(at 162.56 127 0)
			(effects
				(font
					(size 1.27 1.27)
					(thickness 0.15)
				)
				(justify left bottom)
				(hide yes)
			)
		)
		(property "Description" "SMD Multilayer Ceramic Capacitor, 1 µF, 10 V, 0402 [1005 Metric], ± 10%, X6S, C"
			(at 147.32 147.32 0)
			(effects
				(font
					(size 1.27 1.27)
				)
				(hide yes)
			)
		)
		(property "MPN" "C1005X6S1A105K050BC"
			(at 165.1 127 0)
			(effects
				(font
					(size 1.27 1.27)
					(thickness 0.15)
				)
				(justify left bottom)
				(hide yes)
			)
		)
		(property "Manufacturer" "TDK"
			(at 167.64 127 0)
			(effects
				(font
					(size 1.27 1.27)
					(thickness 0.15)
				)
				(justify left bottom)
				(hide yes)
			)
		)
		(property "License" "Apache-2.0"
			(at 170.18 127 0)
			(effects
				(font
					(size 1.27 1.27)
					(thickness 0.15)
				)
				(justify left bottom)
				(hide yes)
			)
		)
		(property "Val" "1u"
			(at 147.955 146.685 90)
			(effects
				(font
					(size 1.27 1.27)
					(thickness 0.15)
				)
				(justify right)
			)
		)
		(property "Voltage" ""
			(at 175.26 127 0)
			(effects
				(font
					(size 1.27 1.27)
				)
				(justify left bottom)
				(hide yes)
			)
		)
		(property "Dielectric" ""
			(at 177.8 127 0)
			(effects
				(font
					(size 1.27 1.27)
				)
				(justify left bottom)
				(hide yes)
			)
		)
		(property "Author" "Antmicro"
			(at 172.72 127 0)
			(effects
				(font
					(size 1.27 1.27)
					(thickness 0.15)
				)
				(justify left bottom)
				(hide yes)
			)
		)
		(pin "1"
		)
		(pin "2"
		)
		(instances
			(project "thunderbolt-to-10gbe-adapter"
				(path ""
					(reference "C58")
					(unit 1)
				)
			)
		)
	)
	(symbol
		(lib_id "antmicroCapacitors0402:C_1u_0402")
		(at 252.73 128.27 90)
		(unit 1)
		(exclude_from_sim no)
		(in_bom yes)
		(on_board yes)
		(dnp no)
		(property "Reference" "C93"
			(at 253.365 123.825 90)
			(effects
				(font
					(size 1.27 1.27)
					(thickness 0.15)
				)
				(justify right)
			)
		)
		(property "Value" "C_1u_0402"
			(at 262.89 107.95 0)
			(effects
				(font
					(size 1.27 1.27)
					(thickness 0.15)
				)
				(justify left bottom)
				(hide yes)
			)
		)
		(property "Footprint" "antmicro-footprints:C_0402_1005Metric"
			(at 265.43 107.95 0)
			(effects
				(font
					(size 1.27 1.27)
					(thickness 0.15)
				)
				(justify left bottom)
				(hide yes)
			)
		)
		(property "Datasheet" "https://product.tdk.com/en/search/capacitor/ceramic/mlcc/info?part_no=C1005X6S1A105K050BC"
			(at 267.97 107.95 0)
			(effects
				(font
					(size 1.27 1.27)
					(thickness 0.15)
				)
				(justify left bottom)
				(hide yes)
			)
		)
		(property "Description" "SMD Multilayer Ceramic Capacitor, 1 µF, 10 V, 0402 [1005 Metric], ± 10%, X6S, C"
			(at 252.73 128.27 0)
			(effects
				(font
					(size 1.27 1.27)
				)
				(hide yes)
			)
		)
		(property "MPN" "C1005X6S1A105K050BC"
			(at 270.51 107.95 0)
			(effects
				(font
					(size 1.27 1.27)
					(thickness 0.15)
				)
				(justify left bottom)
				(hide yes)
			)
		)
		(property "Manufacturer" "TDK"
			(at 273.05 107.95 0)
			(effects
				(font
					(size 1.27 1.27)
					(thickness 0.15)
				)
				(justify left bottom)
				(hide yes)
			)
		)
		(property "License" "Apache-2.0"
			(at 275.59 107.95 0)
			(effects
				(font
					(size 1.27 1.27)
					(thickness 0.15)
				)
				(justify left bottom)
				(hide yes)
			)
		)
		(property "Val" "1u"
			(at 253.365 127.635 90)
			(effects
				(font
					(size 1.27 1.27)
					(thickness 0.15)
				)
				(justify right)
			)
		)
		(property "Voltage" ""
			(at 280.67 107.95 0)
			(effects
				(font
					(size 1.27 1.27)
				)
				(justify left bottom)
				(hide yes)
			)
		)
		(property "Dielectric" ""
			(at 283.21 107.95 0)
			(effects
				(font
					(size 1.27 1.27)
				)
				(justify left bottom)
				(hide yes)
			)
		)
		(property "Author" "Antmicro"
			(at 278.13 107.95 0)
			(effects
				(font
					(size 1.27 1.27)
					(thickness 0.15)
				)
				(justify left bottom)
				(hide yes)
			)
		)
		(pin "1"
		)
		(pin "2"
		)
		(instances
			(project "thunderbolt-to-10gbe-adapter"
				(path ""
					(reference "C93")
					(unit 1)
				)
			)
		)
	)
	(symbol
		(lib_id "antmicroTestPoints:TP_0.75mm_SMD")
		(at 265.43 137.16 90)
		(unit 1)
		(exclude_from_sim no)
		(in_bom no)
		(on_board yes)
		(dnp no)
		(fields_autoplaced yes)
		(property "Reference" "TP4"
			(at 267.97 133.985 90)
			(effects
				(font
					(size 1.27 1.27)
					(thickness 0.15)
				)
				(justify right)
			)
		)
		(property "Value" "TP_0.75mm_SMD"
			(at 269.24 127 0)
			(effects
				(font
					(size 1.27 1.27)
					(thickness 0.15)
				)
				(justify left bottom)
				(hide yes)
			)
		)
		(property "Footprint" "antmicro-footprints:TP_SMD_0.75mm"
			(at 271.78 127 0)
			(effects
				(font
					(size 1.27 1.27)
					(thickness 0.15)
				)
				(justify left bottom)
				(hide yes)
			)
		)
		(property "Datasheet" ""
			(at 278.13 119.38 0)
			(effects
				(font
					(size 1.27 1.27)
					(thickness 0.15)
				)
				(justify left bottom)
				(hide yes)
			)
		)
		(property "Description" "SMT test point"
			(at 279.4 126.365 0)
			(effects
				(font
					(size 1.27 1.27)
				)
				(justify left bottom)
				(hide yes)
			)
		)
		(property "License" "Apache-2.0"
			(at 276.86 127 0)
			(effects
				(font
					(size 1.27 1.27)
					(thickness 0.15)
				)
				(justify left bottom)
				(hide yes)
			)
		)
		(property "Manufacturer" ""
			(at 271.78 126.365 0)
			(effects
				(font
					(size 1.27 1.27)
					(thickness 0.15)
				)
				(justify left bottom)
				(hide yes)
			)
		)
		(property "MPN" ""
			(at 276.86 126.365 0)
			(effects
				(font
					(size 1.27 1.27)
					(thickness 0.15)
				)
				(justify left bottom)
				(hide yes)
			)
		)
		(property "Author" "Antmicro"
			(at 274.32 127 0)
			(effects
				(font
					(size 1.27 1.27)
					(thickness 0.15)
				)
				(justify left bottom)
				(hide yes)
			)
		)
		(pin "1"
		)
		(instances
			(project "thunderbolt-to-10gbe-adapter"
				(path ""
					(reference "TP4")
					(unit 1)
				)
			)
		)
	)
	(symbol
		(lib_id "antmicropower:PWR_FLAG")
		(at 134.62 119.38 0)
		(unit 1)
		(exclude_from_sim no)
		(in_bom yes)
		(on_board yes)
		(dnp no)
		(property "Reference" "#FLG09"
			(at 134.62 117.475 0)
			(effects
				(font
					(size 1.27 1.27)
				)
				(hide yes)
			)
		)
		(property "Value" "PWR_FLAG"
			(at 143.51 121.92 0)
			(effects
				(font
					(size 1.27 1.27)
				)
				(justify right)
			)
		)
		(property "Footprint" ""
			(at 134.62 119.38 0)
			(effects
				(font
					(size 1.27 1.27)
				)
				(hide yes)
			)
		)
		(property "Datasheet" ""
			(at 134.62 119.38 0)
			(effects
				(font
					(size 1.27 1.27)
				)
				(hide yes)
			)
		)
		(property "Description" ""
			(at 134.62 119.38 0)
			(effects
				(font
					(size 1.27 1.27)
				)
				(hide yes)
			)
		)
		(pin "1"
		)
		(instances
			(project "thunderbolt-to-10gbe-adapter"
				(path ""
					(reference "#FLG09")
					(unit 1)
				)
			)
		)
	)
	(symbol
		(lib_id "antmicropower:GND")
		(at 265.43 80.01 0)
		(unit 1)
		(exclude_from_sim no)
		(in_bom yes)
		(on_board yes)
		(dnp no)
		(property "Reference" "#PWR0139"
			(at 265.43 86.36 0)
			(effects
				(font
					(size 1.27 1.27)
				)
				(hide yes)
			)
		)
		(property "Value" "GND"
			(at 265.43 83.82 0)
			(effects
				(font
					(size 1.27 1.27)
				)
			)
		)
		(property "Footprint" ""
			(at 265.43 80.01 0)
			(effects
				(font
					(size 1.27 1.27)
				)
				(hide yes)
			)
		)
		(property "Datasheet" ""
			(at 265.43 80.01 0)
			(effects
				(font
					(size 1.27 1.27)
				)
				(hide yes)
			)
		)
		(property "Description" ""
			(at 265.43 80.01 0)
			(effects
				(font
					(size 1.27 1.27)
				)
				(hide yes)
			)
		)
		(property "Author" "Antmicro"
			(at 274.32 87.63 0)
			(effects
				(font
					(size 1.27 1.27)
					(thickness 0.15)
				)
				(justify left bottom)
				(hide yes)
			)
		)
		(property "License" "Apache-2.0"
			(at 274.32 90.17 0)
			(effects
				(font
					(size 1.27 1.27)
					(thickness 0.15)
				)
				(justify left bottom)
				(hide yes)
			)
		)
		(pin "1"
		)
		(instances
			(project "thunderbolt-to-10gbe-adapter"
				(path ""
					(reference "#PWR0139")
					(unit 1)
				)
			)
		)
	)
	(symbol
		(lib_id "antmicropower:GND")
		(at 162.56 96.52 0)
		(unit 1)
		(exclude_from_sim no)
		(in_bom yes)
		(on_board yes)
		(dnp no)
		(property "Reference" "#PWR099"
			(at 162.56 102.87 0)
			(effects
				(font
					(size 1.27 1.27)
				)
				(hide yes)
			)
		)
		(property "Value" "GND"
			(at 162.56 100.33 0)
			(effects
				(font
					(size 1.27 1.27)
				)
			)
		)
		(property "Footprint" ""
			(at 162.56 96.52 0)
			(effects
				(font
					(size 1.27 1.27)
				)
				(hide yes)
			)
		)
		(property "Datasheet" ""
			(at 162.56 96.52 0)
			(effects
				(font
					(size 1.27 1.27)
				)
				(hide yes)
			)
		)
		(property "Description" ""
			(at 162.56 96.52 0)
			(effects
				(font
					(size 1.27 1.27)
				)
				(hide yes)
			)
		)
		(property "Author" "Antmicro"
			(at 171.45 104.14 0)
			(effects
				(font
					(size 1.27 1.27)
					(thickness 0.15)
				)
				(justify left bottom)
				(hide yes)
			)
		)
		(property "License" "Apache-2.0"
			(at 171.45 106.68 0)
			(effects
				(font
					(size 1.27 1.27)
					(thickness 0.15)
				)
				(justify left bottom)
				(hide yes)
			)
		)
		(pin "1"
		)
		(instances
			(project "thunderbolt-to-10gbe-adapter"
				(path ""
					(reference "#PWR099")
					(unit 1)
				)
			)
		)
	)
	(symbol
		(lib_id "antmicropower:GND")
		(at 153.67 224.79 0)
		(unit 1)
		(exclude_from_sim no)
		(in_bom yes)
		(on_board yes)
		(dnp no)
		(property "Reference" "#PWR093"
			(at 153.67 231.14 0)
			(effects
				(font
					(size 1.27 1.27)
				)
				(hide yes)
			)
		)
		(property "Value" "GND"
			(at 153.67 228.6 0)
			(effects
				(font
					(size 1.27 1.27)
				)
			)
		)
		(property "Footprint" ""
			(at 153.67 224.79 0)
			(effects
				(font
					(size 1.27 1.27)
				)
				(hide yes)
			)
		)
		(property "Datasheet" ""
			(at 153.67 224.79 0)
			(effects
				(font
					(size 1.27 1.27)
				)
				(hide yes)
			)
		)
		(property "Description" ""
			(at 153.67 224.79 0)
			(effects
				(font
					(size 1.27 1.27)
				)
				(hide yes)
			)
		)
		(property "Author" "Antmicro"
			(at 162.56 232.41 0)
			(effects
				(font
					(size 1.27 1.27)
					(thickness 0.15)
				)
				(justify left bottom)
				(hide yes)
			)
		)
		(property "License" "Apache-2.0"
			(at 162.56 234.95 0)
			(effects
				(font
					(size 1.27 1.27)
					(thickness 0.15)
				)
				(justify left bottom)
				(hide yes)
			)
		)
		(pin "1"
		)
		(instances
			(project "thunderbolt-to-10gbe-adapter"
				(path ""
					(reference "#PWR093")
					(unit 1)
				)
			)
		)
	)
	(symbol
		(lib_id "antmicroCapacitors0402:C_100n_0402")
		(at 269.24 110.49 90)
		(unit 1)
		(exclude_from_sim no)
		(in_bom yes)
		(on_board yes)
		(dnp no)
		(fields_autoplaced yes)
		(property "Reference" "C99"
			(at 271.78 106.6736 90)
			(effects
				(font
					(size 1.27 1.27)
					(thickness 0.15)
				)
				(justify right)
			)
		)
		(property "Value" "C_100n_0402"
			(at 279.4 90.17 0)
			(effects
				(font
					(size 1.27 1.27)
					(thickness 0.15)
				)
				(justify left bottom)
				(hide yes)
			)
		)
		(property "Footprint" "antmicro-footprints:C_0402_1005Metric"
			(at 281.94 90.17 0)
			(effects
				(font
					(size 1.27 1.27)
					(thickness 0.15)
				)
				(justify left bottom)
				(hide yes)
			)
		)
		(property "Datasheet" "https://www.murata.com/products/productdetail?partno=GRM155R61H104KE14%23"
			(at 284.48 90.17 0)
			(effects
				(font
					(size 1.27 1.27)
					(thickness 0.15)
				)
				(justify left bottom)
				(hide yes)
			)
		)
		(property "Description" "SMD Multilayer Ceramic Capacitor, 0.1 µF, 50 V, 0402 [1005 Metric], ± 10%, X5R, GRM Series"
			(at 269.24 110.49 0)
			(effects
				(font
					(size 1.27 1.27)
				)
				(hide yes)
			)
		)
		(property "MPN" "GRM155R61H104KE14D"
			(at 287.02 90.17 0)
			(effects
				(font
					(size 1.27 1.27)
					(thickness 0.15)
				)
				(justify left bottom)
				(hide yes)
			)
		)
		(property "Manufacturer" "Murata"
			(at 289.56 90.17 0)
			(effects
				(font
					(size 1.27 1.27)
					(thickness 0.15)
				)
				(justify left bottom)
				(hide yes)
			)
		)
		(property "License" "Apache-2.0"
			(at 292.1 90.17 0)
			(effects
				(font
					(size 1.27 1.27)
					(thickness 0.15)
				)
				(justify left bottom)
				(hide yes)
			)
		)
		(property "Val" "100n"
			(at 271.78 109.2136 90)
			(effects
				(font
					(size 1.27 1.27)
					(thickness 0.15)
				)
				(justify right)
			)
		)
		(property "Voltage" "50V"
			(at 297.18 90.17 0)
			(effects
				(font
					(size 1.27 1.27)
				)
				(justify left bottom)
				(hide yes)
			)
		)
		(property "Dielectric" "X5R"
			(at 299.72 90.17 0)
			(effects
				(font
					(size 1.27 1.27)
				)
				(justify left bottom)
				(hide yes)
			)
		)
		(property "Author" "Antmicro"
			(at 294.64 90.17 0)
			(effects
				(font
					(size 1.27 1.27)
					(thickness 0.15)
				)
				(justify left bottom)
				(hide yes)
			)
		)
		(pin "1"
		)
		(pin "2"
		)
		(instances
			(project "thunderbolt-to-10gbe-adapter"
				(path ""
					(reference "C99")
					(unit 1)
				)
			)
		)
	)
	(symbol
		(lib_id "antmicroCapacitors0603:C_22u_0603")
		(at 246.38 147.32 90)
		(unit 1)
		(exclude_from_sim no)
		(in_bom yes)
		(on_board yes)
		(dnp no)
		(property "Reference" "C89"
			(at 247.015 142.875 90)
			(effects
				(font
					(size 1.27 1.27)
					(thickness 0.15)
				)
				(justify right)
			)
		)
		(property "Value" "C_22u_0603"
			(at 256.54 127 0)
			(effects
				(font
					(size 1.27 1.27)
					(thickness 0.15)
				)
				(justify left bottom)
				(hide yes)
			)
		)
		(property "Footprint" "antmicro-footprints:C_0603_1608Metric"
			(at 259.08 127 0)
			(effects
				(font
					(size 1.27 1.27)
					(thickness 0.15)
				)
				(justify left bottom)
				(hide yes)
			)
		)
		(property "Datasheet" "https://www.murata.com/products/productdetail?partno=GRM188R60J226MEA0%23"
			(at 261.62 127 0)
			(effects
				(font
					(size 1.27 1.27)
					(thickness 0.15)
				)
				(justify left bottom)
				(hide yes)
			)
		)
		(property "Description" "SMD Multilayer Ceramic Capacitor, 22 µF, 6.3 V, 0603 [1608 Metric], ± 20%, X5R, GRM Series"
			(at 246.38 147.32 0)
			(effects
				(font
					(size 1.27 1.27)
				)
				(hide yes)
			)
		)
		(property "MPN" "GRM188R60J226MEA0D"
			(at 264.16 127 0)
			(effects
				(font
					(size 1.27 1.27)
					(thickness 0.15)
				)
				(justify left bottom)
				(hide yes)
			)
		)
		(property "Manufacturer" "Murata"
			(at 266.7 127 0)
			(effects
				(font
					(size 1.27 1.27)
					(thickness 0.15)
				)
				(justify left bottom)
				(hide yes)
			)
		)
		(property "License" "Apache-2.0"
			(at 269.24 127 0)
			(effects
				(font
					(size 1.27 1.27)
					(thickness 0.15)
				)
				(justify left bottom)
				(hide yes)
			)
		)
		(property "Val" "22u"
			(at 247.015 146.685 90)
			(effects
				(font
					(size 1.27 1.27)
					(thickness 0.15)
				)
				(justify right)
			)
		)
		(property "Voltage" ""
			(at 274.32 127 0)
			(effects
				(font
					(size 1.27 1.27)
				)
				(justify left bottom)
				(hide yes)
			)
		)
		(property "Dielectric" ""
			(at 276.86 127 0)
			(effects
				(font
					(size 1.27 1.27)
				)
				(justify left bottom)
				(hide yes)
			)
		)
		(property "Author" "Antmicro"
			(at 271.78 127 0)
			(effects
				(font
					(size 1.27 1.27)
					(thickness 0.15)
				)
				(justify left bottom)
				(hide yes)
			)
		)
		(pin "1"
		)
		(pin "2"
		)
		(instances
			(project "thunderbolt-to-10gbe-adapter"
				(path ""
					(reference "C89")
					(unit 1)
				)
			)
		)
	)
	(symbol
		(lib_id "antmicroOperationalAmplifiers:MCP6541_SOT23-5")
		(at 279.4 158.75 0)
		(unit 1)
		(exclude_from_sim no)
		(in_bom yes)
		(on_board yes)
		(dnp no)
		(property "Reference" "U6"
			(at 283.21 163.83 0)
			(effects
				(font
					(size 1.27 1.27)
					(thickness 0.15)
				)
			)
		)
		(property "Value" "MCP6541_SOT23-5"
			(at 304.8 166.37 0)
			(effects
				(font
					(size 1.27 1.27)
					(thickness 0.15)
				)
				(justify left bottom)
				(hide yes)
			)
		)
		(property "Footprint" "antmicro-footprints:SOT-23-5"
			(at 304.8 168.91 0)
			(effects
				(font
					(size 1.27 1.27)
					(thickness 0.15)
				)
				(justify left bottom)
				(hide yes)
			)
		)
		(property "Datasheet" "https://www.farnell.com/datasheets/1641674.pdf"
			(at 304.8 171.45 0)
			(effects
				(font
					(size 1.27 1.27)
					(thickness 0.15)
				)
				(justify left bottom)
				(hide yes)
			)
		)
		(property "Description" "Push-Pull Output Comparator, 1,6V to 5.5V, SOT-23-5"
			(at 279.4 158.75 0)
			(effects
				(font
					(size 1.27 1.27)
				)
				(hide yes)
			)
		)
		(property "MPN" "MCP6541T-E/OT"
			(at 283.21 166.37 0)
			(effects
				(font
					(size 1.27 1.27)
					(thickness 0.15)
				)
			)
		)
		(property "Manufacturer" "Microchip Technology"
			(at 304.8 176.53 0)
			(effects
				(font
					(size 1.27 1.27)
					(thickness 0.15)
				)
				(justify left bottom)
				(hide yes)
			)
		)
		(property "Author" "Antmicro"
			(at 304.8 179.07 0)
			(effects
				(font
					(size 1.27 1.27)
					(thickness 0.15)
				)
				(justify left bottom)
				(hide yes)
			)
		)
		(property "License" "Apache-2.0"
			(at 304.8 181.61 0)
			(effects
				(font
					(size 1.27 1.27)
					(thickness 0.15)
				)
				(justify left bottom)
				(hide yes)
			)
		)
		(pin "1"
		)
		(pin "3"
		)
		(pin "4"
		)
		(pin "2"
		)
		(pin "5"
		)
		(instances
			(project "thunderbolt-to-10gbe-adapter"
				(path ""
					(reference "U6")
					(unit 1)
				)
			)
		)
	)
	(symbol
		(lib_id "antmicroResistors0402:R_8k2_0402")
		(at 262.89 160.02 90)
		(unit 1)
		(exclude_from_sim no)
		(in_bom yes)
		(on_board yes)
		(dnp no)
		(fields_autoplaced yes)
		(property "Reference" "R75"
			(at 265.43 156.21 90)
			(effects
				(font
					(size 1.27 1.27)
					(thickness 0.15)
				)
				(justify right)
			)
		)
		(property "Value" "R_8k2_0402"
			(at 275.59 139.7 0)
			(effects
				(font
					(size 1.27 1.27)
					(thickness 0.15)
				)
				(justify left bottom)
				(hide yes)
			)
		)
		(property "Footprint" "antmicro-footprints:R_0402_1005Metric"
			(at 278.13 139.7 0)
			(effects
				(font
					(size 1.27 1.27)
					(thickness 0.15)
				)
				(justify left bottom)
				(hide yes)
			)
		)
		(property "Datasheet" "https://www.bourns.com/docs/product-datasheets/cr.pdf"
			(at 280.67 139.7 0)
			(effects
				(font
					(size 1.27 1.27)
					(thickness 0.15)
				)
				(justify left bottom)
				(hide yes)
			)
		)
		(property "Description" "SMD Chip Resistor"
			(at 262.89 160.02 0)
			(effects
				(font
					(size 1.27 1.27)
				)
				(hide yes)
			)
		)
		(property "MPN" "CR0402-FX-8201GLF"
			(at 283.21 139.7 0)
			(effects
				(font
					(size 1.27 1.27)
					(thickness 0.15)
				)
				(justify left bottom)
				(hide yes)
			)
		)
		(property "Manufacturer" "Bourns"
			(at 285.75 139.7 0)
			(effects
				(font
					(size 1.27 1.27)
					(thickness 0.15)
				)
				(justify left bottom)
				(hide yes)
			)
		)
		(property "License" "Apache-2.0"
			(at 288.29 139.7 0)
			(effects
				(font
					(size 1.27 1.27)
					(thickness 0.15)
				)
				(justify left bottom)
				(hide yes)
			)
		)
		(property "Author" "Antmicro"
			(at 290.83 139.7 0)
			(effects
				(font
					(size 1.27 1.27)
					(thickness 0.15)
				)
				(justify left bottom)
				(hide yes)
			)
		)
		(property "Val" "8k2"
			(at 265.43 158.75 90)
			(effects
				(font
					(size 1.27 1.27)
					(thickness 0.15)
				)
				(justify right)
			)
		)
		(property "Tolerance" "1%"
			(at 273.05 139.7 0)
			(effects
				(font
					(size 1.27 1.27)
				)
				(justify left bottom)
				(hide yes)
			)
		)
		(pin "1"
		)
		(pin "2"
		)
		(instances
			(project "thunderbolt-to-10gbe-adapter"
				(path ""
					(reference "R75")
					(unit 1)
				)
			)
		)
	)
	(symbol
		(lib_id "antmicroCapacitors0603:C_22u_0603")
		(at 240.03 147.32 90)
		(unit 1)
		(exclude_from_sim no)
		(in_bom yes)
		(on_board yes)
		(dnp no)
		(property "Reference" "C84"
			(at 240.665 142.875 90)
			(effects
				(font
					(size 1.27 1.27)
					(thickness 0.15)
				)
				(justify right)
			)
		)
		(property "Value" "C_22u_0603"
			(at 250.19 127 0)
			(effects
				(font
					(size 1.27 1.27)
					(thickness 0.15)
				)
				(justify left bottom)
				(hide yes)
			)
		)
		(property "Footprint" "antmicro-footprints:C_0603_1608Metric"
			(at 252.73 127 0)
			(effects
				(font
					(size 1.27 1.27)
					(thickness 0.15)
				)
				(justify left bottom)
				(hide yes)
			)
		)
		(property "Datasheet" "https://www.murata.com/products/productdetail?partno=GRM188R60J226MEA0%23"
			(at 255.27 127 0)
			(effects
				(font
					(size 1.27 1.27)
					(thickness 0.15)
				)
				(justify left bottom)
				(hide yes)
			)
		)
		(property "Description" "SMD Multilayer Ceramic Capacitor, 22 µF, 6.3 V, 0603 [1608 Metric], ± 20%, X5R, GRM Series"
			(at 240.03 147.32 0)
			(effects
				(font
					(size 1.27 1.27)
				)
				(hide yes)
			)
		)
		(property "MPN" "GRM188R60J226MEA0D"
			(at 257.81 127 0)
			(effects
				(font
					(size 1.27 1.27)
					(thickness 0.15)
				)
				(justify left bottom)
				(hide yes)
			)
		)
		(property "Manufacturer" "Murata"
			(at 260.35 127 0)
			(effects
				(font
					(size 1.27 1.27)
					(thickness 0.15)
				)
				(justify left bottom)
				(hide yes)
			)
		)
		(property "License" "Apache-2.0"
			(at 262.89 127 0)
			(effects
				(font
					(size 1.27 1.27)
					(thickness 0.15)
				)
				(justify left bottom)
				(hide yes)
			)
		)
		(property "Val" "22u"
			(at 240.665 146.685 90)
			(effects
				(font
					(size 1.27 1.27)
					(thickness 0.15)
				)
				(justify right)
			)
		)
		(property "Voltage" ""
			(at 267.97 127 0)
			(effects
				(font
					(size 1.27 1.27)
				)
				(justify left bottom)
				(hide yes)
			)
		)
		(property "Dielectric" ""
			(at 270.51 127 0)
			(effects
				(font
					(size 1.27 1.27)
				)
				(justify left bottom)
				(hide yes)
			)
		)
		(property "Author" "Antmicro"
			(at 265.43 127 0)
			(effects
				(font
					(size 1.27 1.27)
					(thickness 0.15)
				)
				(justify left bottom)
				(hide yes)
			)
		)
		(pin "1"
		)
		(pin "2"
		)
		(instances
			(project "thunderbolt-to-10gbe-adapter"
				(path ""
					(reference "C84")
					(unit 1)
				)
			)
		)
	)
)
